G04 ================== begin FILE IDENTIFICATION RECORD ==================*
G04 Layout Name:  D:/<user>/Wistron_project/16347-sc/gbr/16347-sc.brd*
G04 Film Name:    TSMD*
G04 File Format:  Gerber RS274X*
G04 File Origin:  Cadence Allegro 16.5-S056*
G04 Origin Date:  Tue Mar 14 17:08:20 2017*
G04 *
G04 Layer:  VIA CLASS/PASTEMASK_TOP*
G04 Layer:  PIN/PASTEMASK_TOP*
G04 Layer:  PACKAGE GEOMETRY/PASTEMASK_TOP*
G04 Layer:  DRAWING FORMAT/LAYER_PCB_STORY*
G04 Layer:  DRAWING FORMAT/LAYER_PAST_T*
G04 Layer:  BOARD GEOMETRY/PANEL_OUTLINE*
G04 *
G04 Offset:    (0.00 0.00)*
G04 Mirror:    No*
G04 Mode:      Positive*
G04 Rotation:  0*
G04 FullContactRelief:  No*
G04 UndefLineWidth:     6.00*
G04 ================== end FILE IDENTIFICATION RECORD ====================*
%FSLAX35Y35*MOIN*%
%IR0*IPPOS*OFA0.00000B0.00000*MIA0B0*SFA1.00000B1.00000*%
%ADD10C,.04*%
%ADD12C,.026*%
%ADD11R,.028X.034*%
%ADD13C,.02*%
%ADD14C,.006*%
G75*
%LPD*%
G75*
G54D10*
X35851Y28624D03*
X48411Y920770D03*
X693601Y10159D03*
X751130Y826309D03*
X765026Y19107D03*
G54D11*
X55513Y61930D03*
X51573D03*
X55513Y56180D03*
X51573D03*
X179726Y61930D03*
X175786D03*
X179726Y56180D03*
X175786D03*
X303939Y61930D03*
X299999D03*
X303939Y56180D03*
X299999D03*
X424211Y61930D03*
Y56180D03*
X428151Y61930D03*
Y56180D03*
X552364Y61930D03*
X548424D03*
X552364Y56180D03*
X548424D03*
X676576Y61930D03*
X672636D03*
X676576Y56180D03*
X672636D03*
G54D12*
X53632Y45628D03*
X97400Y24300D03*
X176835Y43904D03*
X179708Y49915D03*
X173169Y49700D03*
X171596Y44154D03*
X207900Y43000D03*
X296600Y47000D03*
X387700Y23700D03*
X422646Y46356D03*
X548049Y46414D03*
X671209Y45487D03*
G54D13*
G01X-23515Y-108314D02*
X-55515D01*
G01X-23515Y-124314D02*
Y-204314D01*
G01D02*
X1177585D01*
G01X-27515Y-108314D02*
G02I-12000J0D01*
G01X-39515Y-124314D02*
Y-92314D01*
G01X-23515Y-124314D02*
X1177585D01*
G01X-23515Y-159814D02*
X1177585D01*
G01X-32665Y-108314D02*
G02I-6850J0D01*
G01X390085Y-124314D02*
Y-204314D01*
G01X527585Y-124314D02*
Y-204314D01*
G01X642585Y-124314D02*
Y-204314D01*
G01X810085Y-124314D02*
Y-204314D01*
G01X980085Y-124314D02*
Y-204314D01*
G01X1177585Y-124314D02*
Y-204314D01*
G01X1205585Y-108314D02*
G02I-12000J0D01*
G01X1200435D02*
G02I-6850J0D01*
G01X1209585D02*
X1177585D01*
G01X1193585Y-124314D02*
Y-92314D01*
G54D14*
G01X981Y-184981D02*
X1855Y-184106D01*
X2510Y-182648D01*
X2947Y-180605D01*
X2510Y-178856D01*
X1637Y-177689D01*
X108Y-176814D01*
X-5787D01*
Y-194314D01*
X1418D01*
X2947Y-193148D01*
X3820Y-191397D01*
X4257Y-189356D01*
X3820Y-187314D01*
X2510Y-185564D01*
X981Y-184981D01*
X-5787D01*
G01X13678Y-194314D02*
Y-182648D01*
G01Y-184981D02*
X14770Y-183814D01*
X15862Y-182939D01*
X17390Y-182648D01*
X18481Y-182939D01*
X19792Y-183814D01*
G01X29650Y-199564D02*
X30960Y-200147D01*
X32707Y-199564D01*
X33798Y-198398D01*
X34672Y-196939D01*
X35981Y-192273D01*
X38820Y-182648D01*
G01X31833D02*
X35981Y-192273D01*
G01X55228Y-184106D02*
X53700Y-182939D01*
X52390Y-182648D01*
X50643Y-183231D01*
X49333Y-184397D01*
X48460Y-186439D01*
X48241Y-188481D01*
X48460Y-190523D01*
X49333Y-192273D01*
X50643Y-193731D01*
X52390Y-194314D01*
X53918Y-193731D01*
X55228Y-192564D01*
G01X65960Y-186439D02*
X72947D01*
X72292Y-184397D01*
X71200Y-183231D01*
X69672Y-182648D01*
X68143Y-182939D01*
X66833Y-183814D01*
X65960Y-185856D01*
X65523Y-187606D01*
Y-189356D01*
X65960Y-191106D01*
X67052Y-192856D01*
X68362Y-194022D01*
X69890Y-194314D01*
X71418Y-193731D01*
X72947Y-191981D01*
G01X109038Y-178273D02*
X107728Y-177397D01*
X106200Y-176814D01*
X104453D01*
X102488Y-177689D01*
X100960Y-179147D01*
X99868Y-180898D01*
X98995Y-183814D01*
X98776Y-186439D01*
X99213Y-189064D01*
X99868Y-190814D01*
X101178Y-192564D01*
X102707Y-193731D01*
X104235Y-194314D01*
X105763D01*
X107292Y-193731D01*
X108602Y-192856D01*
X109694Y-191690D01*
G01X125665Y-194314D02*
Y-182648D01*
G01Y-184689D02*
X124792Y-183523D01*
X123481Y-182939D01*
X121953Y-182648D01*
X120425Y-183231D01*
X119115Y-184397D01*
X118241Y-186147D01*
X117805Y-188481D01*
X118241Y-190814D01*
X119115Y-192564D01*
X120425Y-193731D01*
X121953Y-194314D01*
X123481Y-194022D01*
X124792Y-193148D01*
X125665Y-191981D01*
G01X135523Y-194314D02*
Y-182648D01*
G01Y-185564D02*
X136397Y-184106D01*
X137707Y-182939D01*
X139453Y-182648D01*
X140981Y-182939D01*
X142292Y-184106D01*
X142947Y-186147D01*
Y-194314D01*
G01X152150Y-199564D02*
X153460Y-200147D01*
X155207Y-199564D01*
X156298Y-198398D01*
X157172Y-196939D01*
X158481Y-192273D01*
X161320Y-182648D01*
G01X154333D02*
X158481Y-192273D01*
G01X174235Y-194314D02*
X172925Y-194022D01*
X171615Y-192856D01*
X170741Y-190814D01*
X170305Y-188481D01*
X170741Y-186147D01*
X171615Y-184106D01*
X172925Y-182939D01*
X174235Y-182648D01*
X175545Y-182939D01*
X176855Y-184106D01*
X177728Y-186147D01*
X177947Y-188481D01*
X177728Y-190814D01*
X176855Y-192856D01*
X175545Y-194022D01*
X174235Y-194314D01*
G01X188023D02*
Y-182648D01*
G01Y-185564D02*
X188897Y-184106D01*
X190207Y-182939D01*
X191953Y-182648D01*
X193481Y-182939D01*
X194792Y-184106D01*
X195447Y-186147D01*
Y-194314D01*
G01X222368Y-176814D02*
Y-194314D01*
X231102D01*
G01X248602D02*
X239868D01*
Y-176814D01*
X248602D01*
G01X245108Y-185272D02*
X239868D01*
G01X256932Y-194314D02*
Y-176814D01*
X261298D01*
X263045Y-177689D01*
X264355Y-178856D01*
X265447Y-180605D01*
X266320Y-182648D01*
X266538Y-185564D01*
X266320Y-188481D01*
X265447Y-190523D01*
X264355Y-192273D01*
X263045Y-193439D01*
X261298Y-194314D01*
X256932D01*
G01X298481Y-184981D02*
X299355Y-184106D01*
X300010Y-182648D01*
X300447Y-180605D01*
X300010Y-178856D01*
X299137Y-177689D01*
X297608Y-176814D01*
X291713D01*
Y-194314D01*
X298918D01*
X300447Y-193148D01*
X301320Y-191397D01*
X301757Y-189356D01*
X301320Y-187314D01*
X300010Y-185564D01*
X298481Y-184981D01*
X291713D01*
G01X314235Y-194314D02*
X312925Y-194022D01*
X311615Y-192856D01*
X310741Y-190814D01*
X310305Y-188481D01*
X310741Y-186147D01*
X311615Y-184106D01*
X312925Y-182939D01*
X314235Y-182648D01*
X315545Y-182939D01*
X316855Y-184106D01*
X317728Y-186147D01*
X317947Y-188481D01*
X317728Y-190814D01*
X316855Y-192856D01*
X315545Y-194022D01*
X314235Y-194314D01*
G01X335665D02*
Y-182648D01*
G01Y-184689D02*
X334792Y-183523D01*
X333481Y-182939D01*
X331953Y-182648D01*
X330425Y-183231D01*
X329115Y-184397D01*
X328241Y-186147D01*
X327805Y-188481D01*
X328241Y-190814D01*
X329115Y-192564D01*
X330425Y-193731D01*
X331953Y-194314D01*
X333481Y-194022D01*
X334792Y-193148D01*
X335665Y-191981D01*
G01X346178Y-194314D02*
Y-182648D01*
G01Y-184981D02*
X347270Y-183814D01*
X348362Y-182939D01*
X349890Y-182648D01*
X350981Y-182939D01*
X352292Y-183814D01*
G01X370665Y-176814D02*
Y-194314D01*
G01Y-191690D02*
X369792Y-193148D01*
X368481Y-194022D01*
X366953Y-194314D01*
X365207Y-193731D01*
X363897Y-192273D01*
X363023Y-190523D01*
X362805Y-188481D01*
X363023Y-186439D01*
X363897Y-184689D01*
X365207Y-183231D01*
X366953Y-182648D01*
X368481Y-182939D01*
X369573Y-183523D01*
X370665Y-184689D01*
G01X142308Y-149314D02*
Y-131814D01*
X147985Y-146397D01*
X153662Y-131814D01*
Y-149314D01*
G01X165485D02*
X164175Y-149022D01*
X162865Y-147856D01*
X161991Y-145814D01*
X161555Y-143481D01*
X161991Y-141147D01*
X162865Y-139106D01*
X164175Y-137939D01*
X165485Y-137648D01*
X166795Y-137939D01*
X168105Y-139106D01*
X168978Y-141147D01*
X169197Y-143481D01*
X168978Y-145814D01*
X168105Y-147856D01*
X166795Y-149022D01*
X165485Y-149314D01*
G01X186915Y-131814D02*
Y-149314D01*
G01Y-146690D02*
X186042Y-148148D01*
X184731Y-149022D01*
X183203Y-149314D01*
X181457Y-148731D01*
X180147Y-147273D01*
X179273Y-145523D01*
X179055Y-143481D01*
X179273Y-141439D01*
X180147Y-139689D01*
X181457Y-138231D01*
X183203Y-137648D01*
X184731Y-137939D01*
X185823Y-138523D01*
X186915Y-139689D01*
G01X197210Y-141439D02*
X204197D01*
X203542Y-139397D01*
X202450Y-138231D01*
X200922Y-137648D01*
X199393Y-137939D01*
X198083Y-138814D01*
X197210Y-140856D01*
X196773Y-142606D01*
Y-144356D01*
X197210Y-146106D01*
X198302Y-147856D01*
X199612Y-149022D01*
X201140Y-149314D01*
X202668Y-148731D01*
X204197Y-146981D01*
G01X217985Y-149314D02*
Y-131814D01*
G01X423785Y-194314D02*
Y-176814D01*
X421165Y-180314D01*
G01Y-194314D02*
X426405D01*
G01X437137Y-187023D02*
X438665Y-184981D01*
X439975Y-183814D01*
X441722Y-183231D01*
X443250Y-183814D01*
X444342Y-184981D01*
X445215Y-186731D01*
X445433Y-188772D01*
X445215Y-190523D01*
X444342Y-192273D01*
X443031Y-193731D01*
X441503Y-194314D01*
X439757Y-193731D01*
X438228Y-191981D01*
X437355Y-189356D01*
X437137Y-186439D01*
X437573Y-182648D01*
X438228Y-180605D01*
X439320Y-178564D01*
X440848Y-177106D01*
X442377Y-176814D01*
X443905Y-177397D01*
X444997Y-178856D01*
G01X453982Y-190814D02*
X455291Y-192856D01*
X457038Y-194022D01*
X459003Y-194314D01*
X460750Y-194022D01*
X462497Y-192564D01*
X463588Y-190814D01*
X463807Y-189064D01*
X463370Y-187023D01*
X461842Y-185564D01*
X460313Y-184981D01*
X458348D01*
G01X460313D02*
X461623Y-184106D01*
X462715Y-182648D01*
X463152Y-180898D01*
X462715Y-179147D01*
X461623Y-177689D01*
X459658Y-176814D01*
X457693Y-177106D01*
X455728Y-178273D01*
G01X478905Y-194314D02*
Y-176814D01*
X470826Y-189356D01*
X481744D01*
G01X493348Y-194314D02*
X493785Y-190523D01*
X494440Y-187314D01*
X495313Y-184397D01*
X496405Y-181189D01*
X498152Y-176814D01*
X489418D01*
G01X410668Y-149314D02*
Y-131814D01*
X415908D01*
X417655Y-132689D01*
X418965Y-134731D01*
X419402Y-137064D01*
X418965Y-139397D01*
X417873Y-141147D01*
X415908Y-142023D01*
X410668D01*
G01X437338Y-133273D02*
X436028Y-132397D01*
X434500Y-131814D01*
X432753D01*
X430788Y-132689D01*
X429260Y-134147D01*
X428168Y-135898D01*
X427295Y-138814D01*
X427076Y-141439D01*
X427513Y-144064D01*
X428168Y-145814D01*
X429478Y-147564D01*
X431007Y-148731D01*
X432535Y-149314D01*
X434063D01*
X435592Y-148731D01*
X436902Y-147856D01*
X437994Y-146690D01*
G01X451781Y-139981D02*
X452655Y-139106D01*
X453310Y-137648D01*
X453747Y-135605D01*
X453310Y-133856D01*
X452437Y-132689D01*
X450908Y-131814D01*
X445013D01*
Y-149314D01*
X452218D01*
X453747Y-148148D01*
X454620Y-146397D01*
X455057Y-144356D01*
X454620Y-142314D01*
X453310Y-140564D01*
X451781Y-139981D01*
X445013D01*
G01X460985Y-155147D02*
X474085D01*
G01X480013Y-149314D02*
Y-131814D01*
X490057Y-149314D01*
Y-131814D01*
G01X502535Y-149314D02*
X500788Y-149022D01*
X499260Y-147856D01*
X497950Y-146106D01*
X497076Y-144064D01*
X496640Y-141731D01*
Y-139397D01*
X497076Y-137064D01*
X497950Y-135022D01*
X499260Y-133273D01*
X500788Y-132106D01*
X502535Y-131814D01*
X504281Y-132106D01*
X505810Y-133273D01*
X507120Y-135022D01*
X507994Y-137064D01*
X508430Y-139397D01*
Y-141731D01*
X507994Y-144064D01*
X507120Y-146106D01*
X505810Y-147856D01*
X504281Y-149022D01*
X502535Y-149314D01*
G01X553376Y-131814D02*
X558835Y-149314D01*
X564294Y-131814D01*
G01X580702Y-149314D02*
X571968D01*
Y-131814D01*
X580702D01*
G01X577208Y-140272D02*
X571968D01*
G01X589468Y-149314D02*
Y-131814D01*
X594927D01*
X596673Y-132689D01*
X597765Y-133856D01*
X598202Y-136189D01*
X597765Y-138523D01*
X596455Y-139981D01*
X594927Y-140856D01*
X589468D01*
G01X594927D02*
X598202Y-149314D01*
G01X611335Y-149897D02*
X610898Y-149606D01*
Y-149022D01*
X611335Y-148731D01*
X611772Y-149022D01*
Y-149606D01*
X611335Y-149897D01*
G01X571750Y-191981D02*
X573497Y-193439D01*
X575462Y-194314D01*
X577208D01*
X578955Y-193439D01*
X580265Y-191981D01*
X580920Y-189939D01*
X580483Y-187898D01*
X579392Y-186147D01*
X577427Y-184981D01*
X574807Y-184397D01*
X573278Y-183231D01*
X572623Y-181189D01*
X573060Y-179147D01*
X574152Y-177689D01*
X575680Y-176814D01*
X577208D01*
X578737Y-177397D01*
X580047Y-178856D01*
G01X598638Y-178273D02*
X597328Y-177397D01*
X595800Y-176814D01*
X594053D01*
X592088Y-177689D01*
X590560Y-179147D01*
X589468Y-180898D01*
X588595Y-183814D01*
X588376Y-186439D01*
X588813Y-189064D01*
X589468Y-190814D01*
X590778Y-192564D01*
X592307Y-193731D01*
X593835Y-194314D01*
X595363D01*
X596892Y-193731D01*
X598202Y-192856D01*
X599294Y-191690D01*
G01X700035Y-176814D02*
Y-194314D01*
G01X695013Y-176814D02*
X705057D01*
G01X712950Y-191981D02*
X714697Y-193439D01*
X716662Y-194314D01*
X718408D01*
X720155Y-193439D01*
X721465Y-191981D01*
X722120Y-189939D01*
X721683Y-187898D01*
X720592Y-186147D01*
X718627Y-184981D01*
X716007Y-184397D01*
X714478Y-183231D01*
X713823Y-181189D01*
X714260Y-179147D01*
X715352Y-177689D01*
X716880Y-176814D01*
X718408D01*
X719937Y-177397D01*
X721247Y-178856D01*
G01X729358Y-194314D02*
Y-176814D01*
X735035Y-191397D01*
X740712Y-176814D01*
Y-194314D01*
G01X747732D02*
Y-176814D01*
X752098D01*
X753845Y-177689D01*
X755155Y-178856D01*
X756247Y-180605D01*
X757120Y-182648D01*
X757338Y-185564D01*
X757120Y-188481D01*
X756247Y-190523D01*
X755155Y-192273D01*
X753845Y-193439D01*
X752098Y-194314D01*
X747732D01*
G01X686918Y-131814D02*
Y-149314D01*
X695652D01*
G01X712715D02*
Y-137648D01*
G01Y-139689D02*
X711842Y-138523D01*
X710531Y-137939D01*
X709003Y-137648D01*
X707475Y-138231D01*
X706165Y-139397D01*
X705291Y-141147D01*
X704855Y-143481D01*
X705291Y-145814D01*
X706165Y-147564D01*
X707475Y-148731D01*
X709003Y-149314D01*
X710531Y-149022D01*
X711842Y-148148D01*
X712715Y-146981D01*
G01X721700Y-154564D02*
X723010Y-155147D01*
X724757Y-154564D01*
X725848Y-153398D01*
X726722Y-151939D01*
X728031Y-147273D01*
X730870Y-137648D01*
G01X723883D02*
X728031Y-147273D01*
G01X740510Y-141439D02*
X747497D01*
X746842Y-139397D01*
X745750Y-138231D01*
X744222Y-137648D01*
X742693Y-137939D01*
X741383Y-138814D01*
X740510Y-140856D01*
X740073Y-142606D01*
Y-144356D01*
X740510Y-146106D01*
X741602Y-147856D01*
X742912Y-149022D01*
X744440Y-149314D01*
X745968Y-148731D01*
X747497Y-146981D01*
G01X758228Y-149314D02*
Y-137648D01*
G01Y-139981D02*
X759320Y-138814D01*
X760412Y-137939D01*
X761940Y-137648D01*
X763031Y-137939D01*
X764342Y-138814D01*
G01X851335Y-194314D02*
X849588Y-194022D01*
X848060Y-192856D01*
X846750Y-191106D01*
X845876Y-189064D01*
X845440Y-186731D01*
Y-184397D01*
X845876Y-182064D01*
X846750Y-180022D01*
X848060Y-178273D01*
X849588Y-177106D01*
X851335Y-176814D01*
X853081Y-177106D01*
X854610Y-178273D01*
X855920Y-180022D01*
X856794Y-182064D01*
X857230Y-184397D01*
Y-186731D01*
X856794Y-189064D01*
X855920Y-191106D01*
X854610Y-192856D01*
X853081Y-194022D01*
X851335Y-194314D01*
G01X853081Y-189647D02*
X855702Y-194314D01*
G01X864032Y-176814D02*
Y-189356D01*
X864905Y-191981D01*
X866652Y-193731D01*
X868835Y-194314D01*
X871018Y-193731D01*
X872765Y-191981D01*
X873638Y-189356D01*
Y-176814D01*
G01X883715D02*
X888955D01*
G01X886335D02*
Y-194314D01*
G01X883715D02*
X888955D01*
G01X898813D02*
Y-176814D01*
X908857Y-194314D01*
Y-176814D01*
G01X926138Y-178273D02*
X924828Y-177397D01*
X923300Y-176814D01*
X921553D01*
X919588Y-177689D01*
X918060Y-179147D01*
X916968Y-180898D01*
X916095Y-183814D01*
X915876Y-186439D01*
X916313Y-189064D01*
X916968Y-190814D01*
X918278Y-192564D01*
X919807Y-193731D01*
X921335Y-194314D01*
X922863D01*
X924392Y-193731D01*
X925702Y-192856D01*
X926794Y-191690D01*
G01X938835Y-194314D02*
Y-186439D01*
X934468Y-176814D01*
G01X943202D02*
X938835Y-186439D01*
G01X829032Y-149314D02*
Y-131814D01*
X833398D01*
X835145Y-132689D01*
X836455Y-133856D01*
X837547Y-135605D01*
X838420Y-137648D01*
X838638Y-140564D01*
X838420Y-143481D01*
X837547Y-145523D01*
X836455Y-147273D01*
X835145Y-148439D01*
X833398Y-149314D01*
X829032D01*
G01X848060Y-141439D02*
X855047D01*
X854392Y-139397D01*
X853300Y-138231D01*
X851772Y-137648D01*
X850243Y-137939D01*
X848933Y-138814D01*
X848060Y-140856D01*
X847623Y-142606D01*
Y-144356D01*
X848060Y-146106D01*
X849152Y-147856D01*
X850462Y-149022D01*
X851990Y-149314D01*
X853518Y-148731D01*
X855047Y-146981D01*
G01X865560Y-147273D02*
X866652Y-148439D01*
X868180Y-149314D01*
X869490D01*
X870800Y-148731D01*
X871673Y-147856D01*
X872110Y-146690D01*
X871892Y-144939D01*
X871018Y-144064D01*
X867088Y-142314D01*
X866215Y-140272D01*
X866652Y-138814D01*
X867525Y-137939D01*
X868835Y-137648D01*
X870145Y-137939D01*
X871455Y-138814D01*
G01X886335Y-137648D02*
Y-149314D01*
G01Y-132981D02*
X885898Y-132689D01*
Y-132106D01*
X886335Y-131814D01*
X886772Y-132106D01*
Y-132689D01*
X886335Y-132981D01*
G01X900778Y-153689D02*
X902307Y-154856D01*
X904053Y-155147D01*
X905581Y-154856D01*
X906892Y-153398D01*
X907765Y-151356D01*
Y-137648D01*
G01Y-139981D02*
X906892Y-138814D01*
X905581Y-137939D01*
X904053Y-137648D01*
X902307Y-138231D01*
X901215Y-139397D01*
X900341Y-141439D01*
X899905Y-143481D01*
X900123Y-145231D01*
X900997Y-147273D01*
X902307Y-148731D01*
X904053Y-149314D01*
X905363Y-149022D01*
X906892Y-147856D01*
X907765Y-146690D01*
G01X917623Y-149314D02*
Y-137648D01*
G01Y-140564D02*
X918497Y-139106D01*
X919807Y-137939D01*
X921553Y-137648D01*
X923081Y-137939D01*
X924392Y-139106D01*
X925047Y-141147D01*
Y-149314D01*
G01X935560Y-141439D02*
X942547D01*
X941892Y-139397D01*
X940800Y-138231D01*
X939272Y-137648D01*
X937743Y-137939D01*
X936433Y-138814D01*
X935560Y-140856D01*
X935123Y-142606D01*
Y-144356D01*
X935560Y-146106D01*
X936652Y-147856D01*
X937962Y-149022D01*
X939490Y-149314D01*
X941018Y-148731D01*
X942547Y-146981D01*
G01X953278Y-149314D02*
Y-137648D01*
G01Y-139981D02*
X954370Y-138814D01*
X955462Y-137939D01*
X956990Y-137648D01*
X958081Y-137939D01*
X959392Y-138814D01*
G01X1000035Y-176814D02*
X998288Y-177397D01*
X996978Y-178856D01*
X996105Y-180605D01*
X995450Y-182939D01*
X995232Y-185564D01*
X995450Y-188189D01*
X996105Y-190523D01*
X996978Y-192273D01*
X998288Y-193731D01*
X1000035Y-194314D01*
X1001781Y-193731D01*
X1003092Y-192273D01*
X1003965Y-190523D01*
X1004620Y-188189D01*
X1004838Y-185564D01*
X1004620Y-182939D01*
X1003965Y-180605D01*
X1003092Y-178856D01*
X1001781Y-177397D01*
X1000035Y-176814D01*
G01X1012732Y-190814D02*
X1014041Y-192856D01*
X1015788Y-194022D01*
X1017753Y-194314D01*
X1019500Y-194022D01*
X1021247Y-192564D01*
X1022338Y-190814D01*
X1022557Y-189064D01*
X1022120Y-187023D01*
X1020592Y-185564D01*
X1019063Y-184981D01*
X1017098D01*
G01X1019063D02*
X1020373Y-184106D01*
X1021465Y-182648D01*
X1021902Y-180898D01*
X1021465Y-179147D01*
X1020373Y-177689D01*
X1018408Y-176814D01*
X1016443Y-177106D01*
X1014478Y-178273D01*
G01X1031105Y-194897D02*
X1038965Y-176814D01*
G01X1052535Y-194314D02*
Y-176814D01*
X1049915Y-180314D01*
G01Y-194314D02*
X1055155D01*
G01X1065232Y-190814D02*
X1066541Y-192856D01*
X1068288Y-194022D01*
X1070253Y-194314D01*
X1072000Y-194022D01*
X1073747Y-192564D01*
X1074838Y-190814D01*
X1075057Y-189064D01*
X1074620Y-187023D01*
X1073092Y-185564D01*
X1071563Y-184981D01*
X1069598D01*
G01X1071563D02*
X1072873Y-184106D01*
X1073965Y-182648D01*
X1074402Y-180898D01*
X1073965Y-179147D01*
X1072873Y-177689D01*
X1070908Y-176814D01*
X1068943Y-177106D01*
X1066978Y-178273D01*
G01X1083605Y-194897D02*
X1091465Y-176814D01*
G01X1100887Y-179731D02*
X1102197Y-177981D01*
X1103725Y-177106D01*
X1105472Y-176814D01*
X1107655Y-177397D01*
X1109183Y-178856D01*
X1109620Y-180605D01*
X1109402Y-182356D01*
X1108528Y-183814D01*
X1104162Y-186731D01*
X1102197Y-188772D01*
X1100887Y-191690D01*
X1100450Y-194314D01*
X1109620D01*
G01X1122535Y-176814D02*
X1120788Y-177397D01*
X1119478Y-178856D01*
X1118605Y-180605D01*
X1117950Y-182939D01*
X1117732Y-185564D01*
X1117950Y-188189D01*
X1118605Y-190523D01*
X1119478Y-192273D01*
X1120788Y-193731D01*
X1122535Y-194314D01*
X1124281Y-193731D01*
X1125592Y-192273D01*
X1126465Y-190523D01*
X1127120Y-188189D01*
X1127338Y-185564D01*
X1127120Y-182939D01*
X1126465Y-180605D01*
X1125592Y-178856D01*
X1124281Y-177397D01*
X1122535Y-176814D01*
G01X1140035Y-194314D02*
Y-176814D01*
X1137415Y-180314D01*
G01Y-194314D02*
X1142655D01*
G01X1157098D02*
X1157535Y-190523D01*
X1158190Y-187314D01*
X1159063Y-184397D01*
X1160155Y-181189D01*
X1161902Y-176814D01*
X1153168D01*
G01X1047732Y-149314D02*
Y-131814D01*
X1052098D01*
X1053845Y-132689D01*
X1055155Y-133856D01*
X1056247Y-135605D01*
X1057120Y-137648D01*
X1057338Y-140564D01*
X1057120Y-143481D01*
X1056247Y-145523D01*
X1055155Y-147273D01*
X1053845Y-148439D01*
X1052098Y-149314D01*
X1047732D01*
G01X1073965D02*
Y-137648D01*
G01Y-139689D02*
X1073092Y-138523D01*
X1071781Y-137939D01*
X1070253Y-137648D01*
X1068725Y-138231D01*
X1067415Y-139397D01*
X1066541Y-141147D01*
X1066105Y-143481D01*
X1066541Y-145814D01*
X1067415Y-147564D01*
X1068725Y-148731D01*
X1070253Y-149314D01*
X1071781Y-149022D01*
X1073092Y-148148D01*
X1073965Y-146981D01*
G01X1087535Y-131814D02*
Y-149314D01*
G01X1084478Y-137648D02*
X1090592D01*
G01X1101760Y-141439D02*
X1108747D01*
X1108092Y-139397D01*
X1107000Y-138231D01*
X1105472Y-137648D01*
X1103943Y-137939D01*
X1102633Y-138814D01*
X1101760Y-140856D01*
X1101323Y-142606D01*
Y-144356D01*
X1101760Y-146106D01*
X1102852Y-147856D01*
X1104162Y-149022D01*
X1105690Y-149314D01*
X1107218Y-148731D01*
X1108747Y-146981D01*
G01X21279Y19685D02*
G03X11201I-5039J0D01*
G01D02*
G03X21279I5039J0D01*
G01X3937Y-3937D02*
X724409D01*
G01X0Y0D02*
G03X3937Y-3937I3937J0D01*
G01X0Y35433D02*
Y0D01*
G01Y51181D02*
G03X3937Y47244I3937J0D01*
G01X0Y51181D02*
Y118898D01*
G01X4724Y47244D02*
X3937D01*
G01X29921Y63780D02*
Y47244D01*
G01X41732Y75591D02*
G03X29921Y63780I0J-11811D01*
G01X4724Y39370D02*
G03Y47244I0J3937D01*
G01X29921D02*
G03Y39370I0J-3937D01*
G01X3937D02*
G03X0Y35433I0J-3937D01*
G01X33858Y39370D02*
X3937D01*
G01X33858D02*
G03X37795Y43307I0J3937D01*
G01Y63780D02*
Y43307D01*
G01X41732Y67717D02*
G03X37795Y63780I0J-3937D01*
G01X65354Y67717D02*
X41732D01*
G01X3937Y122835D02*
G03X0Y118898I0J-3937D01*
G01X60828Y75591D02*
X41732D01*
G01X20531Y99213D02*
G03I-4291J0D01*
G01X29921Y122835D02*
X60828D01*
G01X21279Y154331D02*
G03X11201I-5039J0D01*
G01D02*
G03X21279I5039J0D01*
G01X3937Y130709D02*
X724409D01*
G01X0Y134646D02*
G03X3937Y130709I3937J0D01*
G01X0Y170079D02*
Y134646D01*
G01X4724Y122835D02*
G03Y130709I0J3937D01*
G01X29921D02*
G03Y122835I0J-3937D01*
G01X4724D02*
X3937D01*
G01X0Y185827D02*
G03X3937Y181890I3937J0D01*
G01X0Y185827D02*
Y253544D01*
G01X4724Y181890D02*
X3937D01*
G01X29921Y198426D02*
Y181890D01*
G01X41732Y210237D02*
G03X29921Y198426I0J-11811D01*
G01X60828Y210237D02*
X41732D01*
G01X4724Y174016D02*
G03Y181890I0J3937D01*
G01X29921D02*
G03Y174016I0J-3937D01*
G01X3937D02*
G03X0Y170079I0J-3937D01*
G01X33858Y174016D02*
X3937D01*
G01X33858D02*
G03X37795Y177953I0J3937D01*
G01Y198426D02*
Y177953D01*
G01X41732Y202363D02*
G03X37795Y198426I0J-3937D01*
G01X65354Y202363D02*
X41732D01*
G01X29921Y257481D02*
X60828D01*
G01X3937D02*
G03X0Y253544I0J-3937D01*
G01X4724Y257481D02*
G03Y265355I0J3937D01*
G01X29921D02*
G03Y257481I0J-3937D01*
G01X4724D02*
X3937D01*
G01X20531Y233859D02*
G03I-4291J0D01*
G01X4724Y308662D02*
G03Y316536I0J3937D01*
G01X29921D02*
G03Y308662I0J-3937D01*
G01X21279Y288977D02*
G03X11201I-5039J0D01*
G01D02*
G03X21279I5039J0D01*
G01X3937Y265355D02*
X724409D01*
G01X0Y269292D02*
G03X3937Y265355I3937J0D01*
G01X0Y304725D02*
Y269292D01*
G01X3937Y308662D02*
G03X0Y304725I0J-3937D01*
G01X33858Y308662D02*
X3937D01*
G01X33858D02*
G03X37795Y312599I0J3937D01*
G01X0Y320473D02*
G03X3937Y316536I3937J0D01*
G01X0Y320473D02*
Y388190D01*
G01X4724Y316536D02*
X3937D01*
G01X29921Y333072D02*
Y316536D01*
G01X41732Y344883D02*
G03X29921Y333072I0J-11811D01*
G01X60828Y344883D02*
X41732D01*
G01X37795Y333072D02*
Y312599D01*
G01X41732Y337009D02*
G03X37795Y333072I0J-3937D01*
G01X65354Y337009D02*
X41732D01*
G01X29921Y392127D02*
X60828D01*
G01X3937D02*
G03X0Y388190I0J-3937D01*
G01X4724Y392127D02*
G03Y400001I0J3937D01*
G01X29921D02*
G03Y392127I0J-3937D01*
G01X4724D02*
X3937D01*
G01X20531Y368505D02*
G03I-4291J0D01*
G01X3937Y400001D02*
X724409D01*
G01X0Y403938D02*
G03X3937Y400001I3937J0D01*
G01X0Y439371D02*
Y403938D01*
G01Y455119D02*
G03X3937Y451182I3937J0D01*
G01X4724D02*
X3937D01*
G01X29921Y467718D02*
Y451182D01*
G01X4724Y443308D02*
G03Y451182I0J3937D01*
G01X29921D02*
G03Y443308I0J-3937D01*
G01X21279Y423623D02*
G03X11201I-5039J0D01*
G01D02*
G03X21279I5039J0D01*
G01X3937Y443308D02*
G03X0Y439371I0J-3937D01*
G01X33858Y443308D02*
X3937D01*
G01X33858D02*
G03X37795Y447245I0J3937D01*
G01Y467718D02*
Y447245D01*
G01X0Y455119D02*
Y522836D01*
G01X41732Y479529D02*
G03X29921Y467718I0J-11811D01*
G01X60828Y479529D02*
X41732D01*
G01X20531Y503151D02*
G03I-4291J0D01*
G01X41732Y471655D02*
G03X37795Y467718I0J-3937D01*
G01X65354Y471655D02*
X41732D01*
G01X29921Y526773D02*
X60828D01*
G01X3937D02*
G03X0Y522836I0J-3937D01*
G01X4724Y526773D02*
G03Y534647I0J3937D01*
G01X29921D02*
G03Y526773I0J-3937D01*
G01X4724D02*
X3937D01*
G01Y534647D02*
X724409D01*
G01X0Y538584D02*
G03X3937Y534647I3937J0D01*
G01X0Y574017D02*
Y538584D01*
G01Y589765D02*
G03X3937Y585828I3937J0D01*
G01X0Y589765D02*
Y657482D01*
G01X4724Y585828D02*
X3937D01*
G01X29921Y602364D02*
Y585828D01*
G01X4724Y577954D02*
G03Y585828I0J3937D01*
G01X29921D02*
G03Y577954I0J-3937D01*
G01X21279Y558269D02*
G03X11201I-5039J0D01*
G01D02*
G03X21279I5039J0D01*
G01X3937Y577954D02*
G03X0Y574017I0J-3937D01*
G01X33858Y577954D02*
X3937D01*
G01X33858D02*
G03X37795Y581891I0J3937D01*
G01Y602364D02*
Y581891D01*
G01X41732Y614175D02*
G03X29921Y602364I0J-11811D01*
G01X60828Y614175D02*
X41732D01*
G01X20531Y637797D02*
G03I-4291J0D01*
G01X41732Y606301D02*
G03X37795Y602364I0J-3937D01*
G01X65354Y606301D02*
X41732D01*
G01X29921Y661419D02*
X60828D01*
G01X3937D02*
G03X0Y657482I0J-3937D01*
G01X4724Y661419D02*
G03Y669293I0J3937D01*
G01X29921D02*
G03Y661419I0J-3937D01*
G01X4724D02*
X3937D01*
G01X11201Y692915D02*
G03X21279I5039J0D01*
G01X3937Y669293D02*
X724409D01*
G01X0Y673230D02*
G03X3937Y669293I3937J0D01*
G01X0Y708663D02*
Y673230D01*
G01Y724411D02*
G03X3937Y720474I3937J0D01*
G01X0Y724411D02*
Y792128D01*
G01X4724Y720474D02*
X3937D01*
G01X29921Y737010D02*
Y720474D01*
G01X41732Y748821D02*
G03X29921Y737010I0J-11811D01*
G01X4724Y712600D02*
G03Y720474I0J3937D01*
G01X29921D02*
G03Y712600I0J-3937D01*
G01X21279Y692915D02*
G03X11201I-5039J0D01*
G01X3937Y712600D02*
G03X0Y708663I0J-3937D01*
G01X33858Y712600D02*
X3937D01*
G01X33858D02*
G03X37795Y716537I0J3937D01*
G01Y737010D02*
Y716537D01*
G01X41732Y740947D02*
G03X37795Y737010I0J-3937D01*
G01X60828Y748821D02*
X41732D01*
G01X20531Y772443D02*
G03I-4291J0D01*
G01X65354Y740947D02*
X41732D01*
G01X29921Y796065D02*
X60828D01*
G01X3937D02*
G03X0Y792128I0J-3937D01*
G01X4724Y796065D02*
G03Y803939I0J3937D01*
G01X29921D02*
G03Y796065I0J-3937D01*
G01X4724D02*
X3937D01*
G01X21279Y827561D02*
G03X11201I-5039J0D01*
G01D02*
G03X21279I5039J0D01*
G01X3937Y803939D02*
X724409D01*
G01X0Y807876D02*
G03X3937Y803939I3937J0D01*
G01X0Y843309D02*
Y807876D01*
G01Y859057D02*
G03X3937Y855120I3937J0D01*
G01X0Y859057D02*
Y922837D01*
G01X4724Y855120D02*
X3937D01*
G01X29921Y871656D02*
Y855120D01*
G01X41732Y883467D02*
G03X29921Y871656I0J-11811D01*
G01X4724Y847246D02*
G03Y855120I0J3937D01*
G01X29921D02*
G03Y847246I0J-3937D01*
G01X3937D02*
G03X0Y843309I0J-3937D01*
G01X33858Y847246D02*
X3937D01*
G01X33858D02*
G03X37795Y851183I0J3937D01*
G01Y871656D02*
Y851183D01*
G01X41732Y875593D02*
G03X37795Y871656I0J-3937D01*
G01X65354Y875593D02*
X41732D01*
G01X7874Y930711D02*
G03X0Y922837I0J-7874D01*
G01X60828Y883467D02*
X41732D01*
G01X20531Y907089D02*
G03I-4291J0D01*
G01X60828Y930711D02*
X7874D01*
G01X53445Y19685D02*
G03X42028I-5709J0D01*
G01D02*
G03X53445I5709J0D01*
G01X69291Y63780D02*
G03X65354Y67717I-3937J0D01*
G01X69291Y43307D02*
Y63780D01*
G01Y43307D02*
G03X73228Y39370I3937J0D01*
G01X156102D02*
X73228D01*
G01X64765Y118898D02*
G03X60828Y122835I-3937J0D01*
G01Y75591D02*
G03X64765Y79528I0J3937D01*
G01Y113780D02*
Y118898D01*
G01X72639Y88583D02*
G03X64765I-3937J0D01*
G01Y113780D02*
G03X72639I3937J0D01*
G01X64765Y88583D02*
Y79528D01*
G01X83879Y99213D02*
G03X93879I5000J0D01*
G01D02*
G03X83879I-5000J0D01*
G01X76576Y122835D02*
G03X72639Y118898I0J-3937D01*
G01X76576Y79528D02*
X106694D01*
G01X72639Y83465D02*
G03X76576Y79528I3937J0D01*
G01X72639Y118898D02*
Y83465D01*
G01X53445Y154331D02*
G03X42028I-5709J0D01*
G01D02*
G03X53445I5709J0D01*
G01X797048Y122835D02*
X76576D01*
G01X60828Y210237D02*
G03X64765Y214174I0J3937D01*
G01Y223229D02*
Y214174D01*
G01X76576D02*
X106694D01*
G01X72639Y218111D02*
G03X76576Y214174I3937J0D01*
G01X69291Y198426D02*
G03X65354Y202363I-3937J0D01*
G01X69291Y177953D02*
Y198426D01*
G01Y177953D02*
G03X73228Y174016I3937J0D01*
G01X156102D02*
X73228D01*
G01X64765Y253544D02*
G03X60828Y257481I-3937J0D01*
G01X64765Y248426D02*
Y253544D01*
G01X72639Y223229D02*
G03X64765I-3937J0D01*
G01Y248426D02*
G03X72639I3937J0D01*
G01X83879Y233859D02*
G03X93879I5000J0D01*
G01D02*
G03X83879I-5000J0D01*
G01X76576Y257481D02*
G03X72639Y253544I0J-3937D01*
G01X797048Y257481D02*
X76576D01*
G01X72639Y253544D02*
Y218111D01*
G01X53445Y288977D02*
G03X42028I-5709J0D01*
G01D02*
G03X53445I5709J0D01*
G01X69291Y312599D02*
G03X73228Y308662I3937J0D01*
G01X156102D02*
X73228D01*
G01X60828Y344883D02*
G03X64765Y348820I0J3937D01*
G01X72639Y357875D02*
G03X64765I-3937J0D01*
G01D02*
Y348820D01*
G01X76576D02*
X106694D01*
G01X72639Y352757D02*
G03X76576Y348820I3937J0D01*
G01X72639Y388190D02*
Y352757D01*
G01X69291Y333072D02*
G03X65354Y337009I-3937J0D01*
G01X69291Y312599D02*
Y333072D01*
G01X64765Y388190D02*
G03X60828Y392127I-3937J0D01*
G01X64765Y383072D02*
Y388190D01*
G01Y383072D02*
G03X72639I3937J0D01*
G01X83879Y368505D02*
G03X93879I5000J0D01*
G01D02*
G03X83879I-5000J0D01*
G01X76576Y392127D02*
G03X72639Y388190I0J-3937D01*
G01X797048Y392127D02*
X76576D01*
G01X53445Y423623D02*
G03X42028I-5709J0D01*
G01D02*
G03X53445I5709J0D01*
G01X69291Y447245D02*
Y467718D01*
G01Y447245D02*
G03X73228Y443308I3937J0D01*
G01X156102D02*
X73228D01*
G01X60828Y479529D02*
G03X64765Y483466I0J3937D01*
G01X72639Y492521D02*
G03X64765I-3937J0D01*
G01D02*
Y483466D01*
G01X83879Y503151D02*
G03X93879I5000J0D01*
G01X76576Y483466D02*
X106694D01*
G01X72639Y487403D02*
G03X76576Y483466I3937J0D01*
G01X72639Y522836D02*
Y487403D01*
G01X69291Y467718D02*
G03X65354Y471655I-3937J0D01*
G01X64765Y522836D02*
G03X60828Y526773I-3937J0D01*
G01X64765Y517718D02*
Y522836D01*
G01Y517718D02*
G03X72639I3937J0D01*
G01X93879Y503151D02*
G03X83879I-5000J0D01*
G01X76576Y526773D02*
G03X72639Y522836I0J-3937D01*
G01X797048Y526773D02*
X76576D01*
G01X53445Y558269D02*
G03X42028I-5709J0D01*
G01D02*
G03X53445I5709J0D01*
G01X69291Y581891D02*
Y602364D01*
G01Y581891D02*
G03X73228Y577954I3937J0D01*
G01X156102D02*
X73228D01*
G01X60828Y614175D02*
G03X64765Y618112I0J3937D01*
G01X72639Y627167D02*
G03X64765I-3937J0D01*
G01D02*
Y618112D01*
G01X83879Y637797D02*
G03X93879I5000J0D01*
G01D02*
G03X83879I-5000J0D01*
G01X76576Y618112D02*
X106694D01*
G01X72639Y622049D02*
G03X76576Y618112I3937J0D01*
G01X72639Y657482D02*
Y622049D01*
G01X69291Y602364D02*
G03X65354Y606301I-3937J0D01*
G01X64765Y657482D02*
G03X60828Y661419I-3937J0D01*
G01X64765Y652364D02*
Y657482D01*
G01Y652364D02*
G03X72639I3937J0D01*
G01X42028Y692915D02*
G03X53445I5709J0D01*
G01X76576Y661419D02*
G03X72639Y657482I0J-3937D01*
G01X797048Y661419D02*
X76576D01*
G01X53445Y692915D02*
G03X42028I-5709J0D01*
G01X69291Y737010D02*
G03X65354Y740947I-3937J0D01*
G01X69291Y716537D02*
Y737010D01*
G01Y716538D02*
G03X73228Y712601I3937J0D01*
G01X156102Y712600D02*
X73228D01*
G01X60828Y748821D02*
G03X64765Y752758I0J3937D01*
G01Y787010D02*
Y792128D01*
G01X72639Y761813D02*
G03X64765I-3937J0D01*
G01Y787010D02*
G03X72639I3937J0D01*
G01X64765Y761813D02*
Y752758D01*
G01X83879Y772443D02*
G03X93879I5000J0D01*
G01D02*
G03X83879I-5000J0D01*
G01X76576Y752758D02*
X106694D01*
G01X72639Y756695D02*
G03X76576Y752758I3937J0D01*
G01X72639Y792128D02*
Y756695D01*
G01X64765Y792128D02*
G03X60828Y796065I-3937J0D01*
G01X53445Y827561D02*
G03X42028I-5709J0D01*
G01D02*
G03X53445I5709J0D01*
G01X76576Y796065D02*
G03X72639Y792128I0J-3937D01*
G01X797048Y796065D02*
X76576D01*
G01X69291Y871656D02*
G03X65354Y875593I-3937J0D01*
G01X69291Y851183D02*
Y871656D01*
G01Y851184D02*
G03X73228Y847247I3937J0D01*
G01X156102Y847246D02*
X73228D01*
G01X60828Y883467D02*
G03X64765Y887404I0J3937D01*
G01Y926774D02*
G03X60828Y930711I-3937J0D01*
G01X64765Y921656D02*
Y926774D01*
G01X72639Y896459D02*
G03X64765I-3937J0D01*
G01Y921656D02*
G03X72639I3937J0D01*
G01X64765Y896459D02*
Y887404D01*
G01X83879Y907089D02*
G03X93879I5000J0D01*
G01D02*
G03X83879I-5000J0D01*
G01X76576Y930711D02*
G03X72639Y926774I0J-3937D01*
G01X76576Y887404D02*
X106694D01*
G01X72639Y891341D02*
G03X76576Y887404I3937J0D01*
G01X72639Y926774D02*
Y891341D01*
G01X797048Y930711D02*
X76576D01*
G01X114568Y51181D02*
X138190D01*
G01X110631Y55118D02*
G03X114568Y51181I3937J0D01*
G01X110631Y75591D02*
Y55118D01*
G01X114666Y99213D02*
G03X126083I5708J0D01*
G01D02*
G03X114666I-5709J0D01*
G01X110631Y75591D02*
G03X106694Y79528I-3937J0D01*
G01X114568Y185827D02*
X138190D01*
G01X110631Y189764D02*
G03X114568Y185827I3937J0D01*
G01X110631Y210237D02*
Y189764D01*
G01Y210237D02*
G03X106694Y214174I-3937J0D01*
G01X114666Y233859D02*
G03X126083I5708J0D01*
G01D02*
G03X114666I-5709J0D01*
G01X114568Y320473D02*
X138190D01*
G01X110631Y324410D02*
G03X114568Y320473I3937J0D01*
G01X110631Y344883D02*
Y324410D01*
G01Y344883D02*
G03X106694Y348820I-3937J0D01*
G01X114666Y368505D02*
G03X126083I5708J0D01*
G01D02*
G03X114666I-5709J0D01*
G01Y503151D02*
G03X126083I5708J0D01*
G01X114568Y455119D02*
X138190D01*
G01X110631Y459056D02*
G03X114568Y455119I3937J0D01*
G01X110631Y479529D02*
Y459056D01*
G01Y479529D02*
G03X106694Y483466I-3937J0D01*
G01X126083Y503151D02*
G03X114666I-5709J0D01*
G01X114568Y589765D02*
X138190D01*
G01X110631Y593702D02*
G03X114568Y589765I3937J0D01*
G01X110631Y614175D02*
Y593702D01*
G01X114666Y637797D02*
G03X126083I5708J0D01*
G01D02*
G03X114666I-5709J0D01*
G01X110631Y614175D02*
G03X106694Y618112I-3937J0D01*
G01X114568Y724411D02*
X138190D01*
G01X110631Y728348D02*
G03X114568Y724411I3937J0D01*
G01X110631Y748821D02*
Y728348D01*
G01X114666Y772443D02*
G03X126083I5708J0D01*
G01D02*
G03X114666I-5709J0D01*
G01X110631Y748821D02*
G03X106694Y752758I-3937J0D01*
G01X114568Y859057D02*
X138190D01*
G01X110631Y862994D02*
G03X114568Y859057I3937J0D01*
G01X110631Y883467D02*
Y862994D01*
G01X114666Y907089D02*
G03X126083I5708J0D01*
G01D02*
G03X114666I-5709J0D01*
G01X110631Y883467D02*
G03X106694Y887404I-3937J0D01*
G01X142127Y55118D02*
Y75591D01*
G01X138190Y51181D02*
G03X142127Y55118I0J3937D01*
G01X180905Y71654D02*
G03Y79528I0J3937D01*
G01X156102Y39370D02*
G03X160039Y43307I0J3937D01*
G01Y67717D02*
Y43307D01*
G01X163976Y71654D02*
G03X160039Y67717I0J-3937D01*
G01X223031Y71654D02*
X163976D01*
G01X146064Y79528D02*
X230906D01*
G01X146064D02*
G03X142127Y75591I0J-3937D01*
G01X146064Y214174D02*
X230906D01*
G01X146064D02*
G03X142127Y210237I0J-3937D01*
G01Y189764D02*
Y210237D01*
G01X138190Y185827D02*
G03X142127Y189764I0J3937D01*
G01X180905Y206300D02*
G03Y214174I0J3937D01*
G01X156102Y174016D02*
G03X160039Y177953I0J3937D01*
G01Y202363D02*
Y177953D01*
G01X163976Y206300D02*
G03X160039Y202363I0J-3937D01*
G01X223031Y206300D02*
X163976D01*
G01X156102Y308662D02*
G03X160039Y312599I0J3937D01*
G01X146064Y348820D02*
X230906D01*
G01X146064D02*
G03X142127Y344883I0J-3937D01*
G01Y324410D02*
Y344883D01*
G01X138190Y320473D02*
G03X142127Y324410I0J3937D01*
G01X180905Y340946D02*
G03Y348820I0J3937D01*
G01X160039Y337009D02*
Y312599D01*
G01X163976Y340946D02*
G03X160039Y337009I0J-3937D01*
G01X223031Y340946D02*
X163976D01*
G01X156102Y443308D02*
G03X160039Y447245I0J3937D01*
G01Y471655D02*
Y447245D01*
G01X146064Y483466D02*
X230906D01*
G01X146064D02*
G03X142127Y479529I0J-3937D01*
G01Y459056D02*
Y479529D01*
G01X138190Y455120D02*
G03X142127Y459057I0J3937D01*
G01X180905Y475592D02*
G03Y483466I0J3937D01*
G01X163976Y475592D02*
G03X160039Y471655I0J-3937D01*
G01X223031Y475592D02*
X163976D01*
G01X142127Y593702D02*
Y614175D01*
G01X138190Y589766D02*
G03X142127Y593703I0J3937D01*
G01X156102Y577954D02*
G03X160039Y581891I0J3937D01*
G01Y606301D02*
Y581891D01*
G01X146064Y618112D02*
X230906D01*
G01X146064D02*
G03X142127Y614175I0J-3937D01*
G01X180905Y610238D02*
G03Y618112I0J3937D01*
G01X163976Y610238D02*
G03X160039Y606301I0J-3937D01*
G01X223031Y610238D02*
X163976D01*
G01X142127Y728348D02*
Y748821D01*
G01X138190Y724412D02*
G03X142127Y728349I0J3937D01*
G01X156102Y712600D02*
G03X160039Y716537I0J3937D01*
G01Y740947D02*
Y716537D01*
G01X146064Y752758D02*
X230906D01*
G01X146064D02*
G03X142127Y748821I0J-3937D01*
G01X180905Y744884D02*
G03Y752758I0J3937D01*
G01X163976Y744884D02*
G03X160039Y740947I0J-3937D01*
G01X223031Y744884D02*
X163976D01*
G01X142127Y862994D02*
Y883467D01*
G01X138190Y859058D02*
G03X142127Y862995I0J3937D01*
G01X180905Y879530D02*
G03Y887404I0J3937D01*
G01X156102Y847246D02*
G03X160039Y851183I0J3937D01*
G01Y875593D02*
Y851183D01*
G01X163976Y879530D02*
G03X160039Y875593I0J-3937D01*
G01X223031Y879530D02*
X163976D01*
G01X146064Y887404D02*
X230906D01*
G01X146064D02*
G03X142127Y883467I0J-3937D01*
G01X206102Y79528D02*
G03Y71654I0J-3937D01*
G01X226969Y67717D02*
G03X223031Y71654I-3937J0D01*
G01X226969Y43307D02*
Y67717D01*
G01Y43307D02*
G03X230906Y39370I3937J0D01*
G01X282283D02*
X230906D01*
G01X234843Y75591D02*
G03X230906Y79528I-3937J0D01*
G01X196309Y122835D02*
G03Y130709I0J3937D01*
G01X221506D02*
G03Y122835I0J-3937D01*
G01X234843Y210237D02*
G03X230906Y214174I-3937J0D01*
G01X206102D02*
G03Y206300I0J-3937D01*
G01X226969Y202363D02*
G03X223031Y206300I-3937J0D01*
G01X226969Y177953D02*
Y202363D01*
G01Y177953D02*
G03X230906Y174016I3937J0D01*
G01X282283D02*
X230906D01*
G01X196309Y257481D02*
G03Y265355I0J3937D01*
G01X221506D02*
G03Y257481I0J-3937D01*
G01X226969Y312599D02*
G03X230906Y308662I3937J0D01*
G01X282283D02*
X230906D01*
G01X234843Y344883D02*
G03X230906Y348820I-3937J0D01*
G01X206102D02*
G03Y340946I0J-3937D01*
G01X226969Y337009D02*
G03X223031Y340946I-3937J0D01*
G01X226969Y312599D02*
Y337009D01*
G01X196309Y392127D02*
G03Y400001I0J3937D01*
G01X221506D02*
G03Y392127I0J-3937D01*
G01X226969Y447245D02*
Y471655D01*
G01Y447245D02*
G03X230906Y443308I3937J0D01*
G01X282283D02*
X230906D01*
G01X234843Y479529D02*
G03X230906Y483466I-3937J0D01*
G01X206102D02*
G03Y475592I0J-3937D01*
G01X226969Y471655D02*
G03X223031Y475592I-3937J0D01*
G01X196309Y526773D02*
G03Y534647I0J3937D01*
G01X221506D02*
G03Y526773I0J-3937D01*
G01X226969Y581891D02*
Y606301D01*
G01Y581891D02*
G03X230906Y577954I3937J0D01*
G01X282283D02*
X230906D01*
G01X234843Y614175D02*
G03X230906Y618112I-3937J0D01*
G01X206102D02*
G03Y610238I0J-3937D01*
G01X226969Y606301D02*
G03X223031Y610238I-3937J0D01*
G01X196309Y661419D02*
G03Y669293I0J3937D01*
G01X221506D02*
G03Y661419I0J-3937D01*
G01X226969Y716537D02*
Y740947D01*
G01Y716537D02*
G03X230906Y712600I3937J0D01*
G01X282283D02*
X230906D01*
G01X234843Y748821D02*
G03X230906Y752758I-3937J0D01*
G01X206102D02*
G03Y744884I0J-3937D01*
G01X226969Y740947D02*
G03X223031Y744884I-3937J0D01*
G01X196309Y796065D02*
G03Y803939I0J3937D01*
G01X221506D02*
G03Y796065I0J-3937D01*
G01X206102Y887404D02*
G03Y879530I0J-3937D01*
G01X226969Y875593D02*
G03X223031Y879530I-3937J0D01*
G01X226969Y851183D02*
Y875593D01*
G01Y851183D02*
G03X230906Y847246I3937J0D01*
G01X282283D02*
X230906D01*
G01X234843Y883467D02*
G03X230906Y887404I-3937J0D01*
G01X266339Y55118D02*
Y75591D01*
G01X262402Y51181D02*
G03X266339Y55118I0J3937D01*
G01X238780Y51181D02*
X262402D01*
G01X234843Y55118D02*
G03X238780Y51181I3937J0D01*
G01X234843Y75591D02*
Y55118D01*
G01X270276Y79528D02*
X355119D01*
G01X270276D02*
G03X266339Y75591I0J-3937D01*
G01X270276Y214174D02*
X355119D01*
G01X270276D02*
G03X266339Y210237I0J-3937D01*
G01Y189764D02*
Y210237D01*
G01X262402Y185827D02*
G03X266339Y189764I0J3937D01*
G01X238780Y185827D02*
X262402D01*
G01X234843Y189764D02*
G03X238780Y185827I3937J0D01*
G01X234843Y210237D02*
Y189764D01*
G01X270276Y348820D02*
X355119D01*
G01X270276D02*
G03X266339Y344883I0J-3937D01*
G01Y324410D02*
Y344883D01*
G01X262402Y320473D02*
G03X266339Y324410I0J3937D01*
G01X238780Y320473D02*
X262402D01*
G01X234843Y324410D02*
G03X238780Y320473I3937J0D01*
G01X234843Y344883D02*
Y324410D01*
G01X270276Y483466D02*
X355119D01*
G01X270276D02*
G03X266339Y479529I0J-3937D01*
G01Y459056D02*
Y479529D01*
G01X262402Y455119D02*
G03X266339Y459056I0J3937D01*
G01X238780Y455119D02*
X262402D01*
G01X234843Y459057D02*
G03X238780Y455120I3937J0D01*
G01X234843Y479529D02*
Y459056D01*
G01X266339Y593702D02*
Y614175D01*
G01X262402Y589765D02*
G03X266339Y593702I0J3937D01*
G01X238780Y589765D02*
X262402D01*
G01X234843Y593703D02*
G03X238780Y589766I3937J0D01*
G01X234843Y614175D02*
Y593702D01*
G01X270276Y618112D02*
X355119D01*
G01X270276D02*
G03X266339Y614175I0J-3937D01*
G01Y728348D02*
Y748821D01*
G01X262402Y724411D02*
G03X266339Y728348I0J3937D01*
G01X238780Y724411D02*
X262402D01*
G01X234843Y728349D02*
G03X238780Y724412I3937J0D01*
G01X234843Y748821D02*
Y728348D01*
G01X270276Y752758D02*
X355119D01*
G01X270276D02*
G03X266339Y748821I0J-3937D01*
G01Y862994D02*
Y883467D01*
G01X262402Y859057D02*
G03X266339Y862994I0J3937D01*
G01X238780Y859057D02*
X262402D01*
G01X234843Y862995D02*
G03X238780Y859058I3937J0D01*
G01X234843Y883467D02*
Y862994D01*
G01X270276Y887404D02*
X355119D01*
G01X270276D02*
G03X266339Y883467I0J-3937D01*
G01X306969Y19685D02*
G03X296969I-5000J0D01*
G01D02*
G03X306969I5000J0D01*
G01X325788Y39370D02*
G03Y47244I0J3937D01*
G01Y71654D02*
G03Y79528I0J3937D01*
G01X325591Y71654D02*
X325788D01*
G01X325591Y47244D02*
Y71654D01*
G01X325788Y47244D02*
X325591D01*
G01X282283Y39370D02*
G03X286220Y43307I0J3937D01*
G01Y63780D02*
Y43307D01*
G01X290157Y67717D02*
G03X286220Y63780I0J-3937D01*
G01X313780Y67717D02*
X290157D01*
G01X317717Y63780D02*
G03X313780Y67717I-3937J0D01*
G01X317717Y43307D02*
Y63780D01*
G01Y43307D02*
G03X321654Y39370I3937J0D01*
G01X406496D02*
X321654D01*
G01X307265Y99213D02*
G03X317343I5039J0D01*
G01D02*
G03X307265I-5039J0D01*
G01X306969Y154331D02*
G03X296969I-5000J0D01*
G01D02*
G03X306969I5000J0D01*
G01X325788Y174016D02*
G03Y181890I0J3937D01*
G01Y206300D02*
G03Y214174I0J3937D01*
G01X325591Y206300D02*
X325788D01*
G01X325591Y181890D02*
Y206300D01*
G01X325788Y181890D02*
X325591D01*
G01X282283Y174016D02*
G03X286220Y177953I0J3937D01*
G01Y198426D02*
Y177953D01*
G01X290157Y202363D02*
G03X286220Y198426I0J-3937D01*
G01X313780Y202363D02*
X290157D01*
G01X317717Y198426D02*
G03X313780Y202363I-3937J0D01*
G01X317717Y177953D02*
Y198426D01*
G01Y177953D02*
G03X321654Y174016I3937J0D01*
G01X406496D02*
X321654D01*
G01X307265Y233859D02*
G03X317343I5039J0D01*
G01D02*
G03X307265I-5039J0D01*
G01X325788Y308662D02*
G03Y316536I0J3937D01*
G01X306969Y288977D02*
G03X296969I-5000J0D01*
G01D02*
G03X306969I5000J0D01*
G01X282283Y308662D02*
G03X286220Y312599I0J3937D01*
G01X317717D02*
G03X321654Y308662I3937J0D01*
G01X406496D02*
X321654D01*
G01X325788Y340946D02*
G03Y348820I0J3937D01*
G01X325591Y340946D02*
X325788D01*
G01X325591Y316536D02*
Y340946D01*
G01X325788Y316536D02*
X325591D01*
G01X286220Y333072D02*
Y312599D01*
G01X290157Y337009D02*
G03X286220Y333072I0J-3937D01*
G01X313780Y337009D02*
X290157D01*
G01X317717Y333072D02*
G03X313780Y337009I-3937J0D01*
G01X317717Y312599D02*
Y333072D01*
G01X307265Y368505D02*
G03X317343I5039J0D01*
G01D02*
G03X307265I-5039J0D01*
G01X325788Y443308D02*
G03Y451182I0J3937D01*
G01X325591D02*
Y475592D01*
G01X325788Y451182D02*
X325591D01*
G01X306969Y423623D02*
G03X296969I-5000J0D01*
G01D02*
G03X306969I5000J0D01*
G01X282283Y443308D02*
G03X286220Y447245I0J3937D01*
G01Y467718D02*
Y447245D01*
G01X317717D02*
Y467718D01*
G01Y447245D02*
G03X321654Y443308I3937J0D01*
G01X406496D02*
X321654D01*
G01X307265Y503151D02*
G03X317343I5039J0D01*
G01X325788Y475592D02*
G03Y483466I0J3937D01*
G01X325591Y475592D02*
X325788D01*
G01X290157Y471655D02*
G03X286220Y467718I0J-3937D01*
G01X313780Y471655D02*
X290157D01*
G01X317717Y467718D02*
G03X313780Y471655I-3937J0D01*
G01X317343Y503151D02*
G03X307265I-5039J0D01*
G01X325788Y577954D02*
G03Y585828I0J3937D01*
G01X325591D02*
Y610238D01*
G01X325788Y585828D02*
X325591D01*
G01X306969Y558269D02*
G03X296969I-5000J0D01*
G01D02*
G03X306969I5000J0D01*
G01X282283Y577954D02*
G03X286220Y581891I0J3937D01*
G01Y602364D02*
Y581891D01*
G01X317717D02*
Y602364D01*
G01Y581891D02*
G03X321654Y577954I3937J0D01*
G01X406496D02*
X321654D01*
G01X307265Y637797D02*
G03X317343I5039J0D01*
G01D02*
G03X307265I-5039J0D01*
G01X325788Y610238D02*
G03Y618112I0J3937D01*
G01X325591Y610238D02*
X325788D01*
G01X290157Y606301D02*
G03X286220Y602364I0J-3937D01*
G01X313780Y606301D02*
X290157D01*
G01X317717Y602364D02*
G03X313780Y606301I-3937J0D01*
G01X296969Y692915D02*
G03X306969I5000J0D01*
G01X325788Y712600D02*
G03Y720474I0J3937D01*
G01X325591D02*
Y744884D01*
G01X325788Y720474D02*
X325591D01*
G01X306969Y692915D02*
G03X296969I-5000J0D01*
G01X282283Y712600D02*
G03X286220Y716537I0J3937D01*
G01Y737010D02*
Y716537D01*
G01X290157Y740947D02*
G03X286220Y737010I0J-3937D01*
G01X317717Y737011D02*
G03X313780Y740947I-3937J-1D01*
G01X317717Y716537D02*
Y737010D01*
G01Y716537D02*
G03X321654Y712600I3937J0D01*
G01X406496D02*
X321654D01*
G01X307265Y772443D02*
G03X317343I5039J0D01*
G01D02*
G03X307265I-5039J0D01*
G01X325788Y744884D02*
G03Y752758I0J3937D01*
G01X325591Y744884D02*
X325788D01*
G01X313780Y740947D02*
X290157D01*
G01X306969Y827561D02*
G03X296969I-5000J0D01*
G01D02*
G03X306969I5000J0D01*
G01X325788Y847246D02*
G03Y855120I0J3937D01*
G01Y879530D02*
G03Y887404I0J3937D01*
G01X325591Y879530D02*
X325788D01*
G01X325591Y855120D02*
Y879530D01*
G01X325788Y855120D02*
X325591D01*
G01X282283Y847246D02*
G03X286220Y851183I0J3937D01*
G01Y871656D02*
Y851183D01*
G01X290157Y875593D02*
G03X286220Y871656I0J-3937D01*
G01X313780Y875593D02*
X290157D01*
G01X317717Y871657D02*
G03X313780Y875593I-3937J-1D01*
G01X317717Y851183D02*
Y871656D01*
G01Y851183D02*
G03X321654Y847246I3937J0D01*
G01X406496D02*
X321654D01*
G01X307265Y907089D02*
G03X317343I5039J0D01*
G01D02*
G03X307265I-5039J0D01*
G01X362993Y51181D02*
X386615D01*
G01X359056Y55118D02*
G03X362993Y51181I3937J0D01*
G01X359056Y75591D02*
Y55118D01*
G01X350985Y71654D02*
X351182D01*
G01X350985Y47244D02*
X351182D01*
G01X350985D02*
G03Y39370I0J-3937D01*
G01Y79528D02*
G03Y71654I0J-3937D01*
G01X351182D02*
Y47244D01*
G01X359056Y75591D02*
G03X355119Y79528I-3937J0D01*
G01X362993Y185827D02*
X386615D01*
G01X359056Y189764D02*
G03X362993Y185827I3937J0D01*
G01X359056Y210237D02*
Y189764D01*
G01Y210237D02*
G03X355119Y214174I-3937J0D01*
G01X350985Y206300D02*
X351182D01*
G01X350985Y181890D02*
X351182D01*
G01X350985D02*
G03Y174016I0J-3937D01*
G01Y214174D02*
G03Y206300I0J-3937D01*
G01X351182D02*
Y181890D01*
G01X350985Y316536D02*
G03Y308662I0J-3937D01*
G01X362993Y320473D02*
X386615D01*
G01X359056Y324410D02*
G03X362993Y320473I3937J0D01*
G01X359056Y344883D02*
Y324410D01*
G01Y344883D02*
G03X355119Y348820I-3937J0D01*
G01X350985Y340946D02*
X351182D01*
G01X350985Y316536D02*
X351182D01*
G01X350985Y348820D02*
G03Y340946I0J-3937D01*
G01X351182D02*
Y316536D01*
G01X350985Y451182D02*
X351182D01*
G01X350985D02*
G03Y443308I0J-3937D01*
G01X351182Y475592D02*
Y451182D01*
G01X362993Y455119D02*
X386615D01*
G01X359056Y459056D02*
G03X362993Y455119I3937J0D01*
G01X359056Y479529D02*
Y459056D01*
G01Y479529D02*
G03X355119Y483466I-3937J0D01*
G01X350985Y475592D02*
X351182D01*
G01X350985Y483466D02*
G03Y475592I0J-3937D01*
G01X362993Y589765D02*
X386615D01*
G01X359056Y593702D02*
G03X362993Y589765I3937J0D01*
G01X359056Y614175D02*
Y593702D01*
G01X350985Y585828D02*
X351182D01*
G01X350985D02*
G03Y577954I0J-3937D01*
G01X351182Y610238D02*
Y585828D01*
G01X359056Y614175D02*
G03X355119Y618112I-3937J0D01*
G01X350985Y610238D02*
X351182D01*
G01X350985Y618112D02*
G03Y610238I0J-3937D01*
G01X362993Y724411D02*
X386615D01*
G01X359056Y728349D02*
G03X362993Y724412I3937J0D01*
G01X359056Y748821D02*
Y728348D01*
G01X350985Y720474D02*
X351182D01*
G01X350985D02*
G03Y712600I0J-3937D01*
G01X351182Y744884D02*
Y720474D01*
G01X359056Y748821D02*
G03X355119Y752758I-3937J0D01*
G01X350985Y744884D02*
X351182D01*
G01X350985Y752758D02*
G03Y744884I0J-3937D01*
G01X362993Y859057D02*
X386615D01*
G01X359056Y862995D02*
G03X362993Y859058I3937J0D01*
G01X359056Y883467D02*
Y862994D01*
G01X350985Y879530D02*
X351182D01*
G01X350985Y855120D02*
X351182D01*
G01X350985D02*
G03Y847246I0J-3937D01*
G01Y887404D02*
G03Y879530I0J-3937D01*
G01X351182D02*
Y855120D01*
G01X359056Y883467D02*
G03X355119Y887404I-3937J0D01*
G01X390552Y55118D02*
Y75591D01*
G01X386615Y51181D02*
G03X390552Y55118I0J3937D01*
G01X406496Y39370D02*
G03X410433Y43307I0J3937D01*
G01Y63780D02*
Y43307D01*
G01X414370Y67717D02*
G03X410433Y63780I0J-3937D01*
G01X437992Y67717D02*
X414370D01*
G01X394489Y79528D02*
X479331D01*
G01X394489D02*
G03X390552Y75591I0J-3937D01*
G01X387894Y122835D02*
G03Y130709I0J3937D01*
G01X413091D02*
G03Y122835I0J-3937D01*
G01X394489Y214174D02*
X479331D01*
G01X394489D02*
G03X390552Y210237I0J-3937D01*
G01Y189764D02*
Y210237D01*
G01X386615Y185827D02*
G03X390552Y189764I0J3937D01*
G01X406496Y174016D02*
G03X410433Y177953I0J3937D01*
G01Y198426D02*
Y177953D01*
G01X414370Y202363D02*
G03X410433Y198426I0J-3937D01*
G01X437992Y202363D02*
X414370D01*
G01X387894Y257481D02*
G03Y265355I0J3937D01*
G01X413091D02*
G03Y257481I0J-3937D01*
G01X406496Y308662D02*
G03X410433Y312599I0J3937D01*
G01X394489Y348820D02*
X479331D01*
G01X394489D02*
G03X390552Y344883I0J-3937D01*
G01Y324410D02*
Y344883D01*
G01X386615Y320473D02*
G03X390552Y324410I0J3937D01*
G01X410433Y333072D02*
Y312599D01*
G01X414370Y337009D02*
G03X410433Y333072I0J-3937D01*
G01X437992Y337009D02*
X414370D01*
G01X387894Y392127D02*
G03Y400001I0J3937D01*
G01X413091D02*
G03Y392127I0J-3937D01*
G01X406496Y443308D02*
G03X410433Y447245I0J3937D01*
G01Y467718D02*
Y447245D01*
G01X394489Y483466D02*
X479331D01*
G01X394489D02*
G03X390552Y479529I0J-3937D01*
G01Y459056D02*
Y479529D01*
G01X386615Y455119D02*
G03X390552Y459056I0J3937D01*
G01X414370Y471655D02*
G03X410433Y467718I0J-3937D01*
G01X437992Y471655D02*
X414370D01*
G01X387894Y526773D02*
G03Y534647I0J3937D01*
G01X413091D02*
G03Y526773I0J-3937D01*
G01X390552Y593702D02*
Y614175D01*
G01X386615Y589765D02*
G03X390552Y593702I0J3937D01*
G01X406496Y577954D02*
G03X410433Y581891I0J3937D01*
G01Y602364D02*
Y581891D01*
G01X394489Y618112D02*
X479331D01*
G01X394489D02*
G03X390552Y614175I0J-3937D01*
G01X414370Y606301D02*
G03X410433Y602364I0J-3937D01*
G01X437992Y606301D02*
X414370D01*
G01X387894Y661419D02*
G03Y669293I0J3937D01*
G01X413091D02*
G03Y661419I0J-3937D01*
G01X390552Y728348D02*
Y748821D01*
G01X386615Y724412D02*
G03X390552Y728349I0J3937D01*
G01X406496Y712600D02*
G03X410433Y716537I0J3937D01*
G01Y737010D02*
Y716537D01*
G01X414370Y740947D02*
G03X410433Y737010I0J-3937D01*
G01X394489Y752758D02*
X479331D01*
G01X394489D02*
G03X390552Y748821I0J-3937D01*
G01X437992Y740947D02*
X414370D01*
G01X387894Y796065D02*
G03Y803939I0J3937D01*
G01X413091D02*
G03Y796065I0J-3937D01*
G01X390552Y862994D02*
Y883467D01*
G01X386615Y859058D02*
G03X390552Y862995I0J3937D01*
G01X406496Y847246D02*
G03X410433Y851183I0J3937D01*
G01Y871656D02*
Y851183D01*
G01X414370Y875593D02*
G03X410433Y871656I0J-3937D01*
G01X437992Y875593D02*
X414370D01*
G01X394489Y887404D02*
X479331D01*
G01X394489D02*
G03X390552Y883467I0J-3937D01*
G01X450000Y47244D02*
X449803D01*
G01X450000Y71654D02*
X449803D01*
G01X450000D02*
G03Y79528I0J3937D01*
G01Y39370D02*
G03Y47244I0J3937D01*
G01X449803D02*
Y71654D01*
G01X441929Y63780D02*
G03X437992Y67717I-3937J0D01*
G01X441929Y43307D02*
Y63780D01*
G01Y43307D02*
G03X445866Y39370I3937J0D01*
G01X530709D02*
X445866D01*
G01X450000Y181890D02*
X449803D01*
G01X450000Y206300D02*
X449803D01*
G01X450000D02*
G03Y214174I0J3937D01*
G01Y174016D02*
G03Y181890I0J3937D01*
G01X449803D02*
Y206300D01*
G01X441929Y198426D02*
G03X437992Y202363I-3937J0D01*
G01X441929Y177953D02*
Y198426D01*
G01Y177953D02*
G03X445866Y174016I3937J0D01*
G01X530709D02*
X445866D01*
G01X450000Y308662D02*
G03Y316536I0J3937D01*
G01X441929Y312599D02*
G03X445866Y308662I3937J0D01*
G01X530709D02*
X445866D01*
G01X450000Y316536D02*
X449803D01*
G01X450000Y340946D02*
X449803D01*
G01X450000D02*
G03Y348820I0J3937D01*
G01X449803Y316536D02*
Y340946D01*
G01X441929Y333072D02*
G03X437992Y337009I-3937J0D01*
G01X441929Y312599D02*
Y333072D01*
G01X450000Y451182D02*
X449803D01*
G01X450000Y443308D02*
G03Y451182I0J3937D01*
G01X449803D02*
Y475592D01*
G01X441929Y447245D02*
Y467718D01*
G01Y447245D02*
G03X445866Y443308I3937J0D01*
G01X530709D02*
X445866D01*
G01X450000Y475592D02*
X449803D01*
G01X450000D02*
G03Y483466I0J3937D01*
G01X441929Y467718D02*
G03X437992Y471655I-3937J0D01*
G01X450000Y585828D02*
X449803D01*
G01X450000Y577954D02*
G03Y585828I0J3937D01*
G01X449803D02*
Y610238D01*
G01X441929Y581891D02*
Y602364D01*
G01Y581891D02*
G03X445866Y577954I3937J0D01*
G01X530709D02*
X445866D01*
G01X450000Y610238D02*
X449803D01*
G01X450000D02*
G03Y618112I0J3937D01*
G01X441929Y602364D02*
G03X437992Y606301I-3937J0D01*
G01X450000Y720474D02*
X449803D01*
G01X450000Y712600D02*
G03Y720474I0J3937D01*
G01X449803D02*
Y744884D01*
G01X441929Y737010D02*
G03X437992Y740947I-3937J0D01*
G01X441929Y716537D02*
Y737010D01*
G01Y716537D02*
G03X445866Y712600I3937J0D01*
G01X530709D02*
X445866D01*
G01X450000Y744884D02*
X449803D01*
G01X450000D02*
G03Y752758I0J3937D01*
G01Y855120D02*
X449803D01*
G01X450000Y879530D02*
X449803D01*
G01X450000D02*
G03Y887404I0J3937D01*
G01Y847246D02*
G03Y855120I0J3937D01*
G01X449803D02*
Y879530D01*
G01X441929Y871656D02*
G03X437992Y875593I-3937J0D01*
G01X441929Y851183D02*
Y871656D01*
G01Y851183D02*
G03X445866Y847246I3937J0D01*
G01X530709D02*
X445866D01*
G01X493720Y19685D02*
G03X483642I-5039J0D01*
G01D02*
G03X493720I5039J0D01*
G01X514765Y55118D02*
Y75591D01*
G01X510828Y51181D02*
G03X514765Y55118I0J3937D01*
G01X487205Y51181D02*
X510828D01*
G01X483269Y55118D02*
G03X487205Y51182I3937J1D01*
G01X483268Y75591D02*
Y55118D01*
G01X475197Y79528D02*
G03Y71654I0J-3937D01*
G01Y47244D02*
G03Y39370I0J-3937D01*
G01X475394Y47244D02*
X475197D01*
G01X475394Y71654D02*
Y47244D01*
G01X475197Y71654D02*
X475394D01*
G01X494017Y99213D02*
G03X504017I5000J0D01*
G01D02*
G03X494017I-5000J0D01*
G01X518702Y79528D02*
X570079D01*
G01X518702D02*
G03X514765Y75591I0J-3937D01*
G01X483268D02*
G03X479331Y79528I-3937J0D01*
G01X493720Y154331D02*
G03X483642I-5039J0D01*
G01D02*
G03X493720I5039J0D01*
G01X518702Y214174D02*
X570079D01*
G01X518702D02*
G03X514765Y210237I0J-3937D01*
G01Y189764D02*
Y210237D01*
G01X510828Y185827D02*
G03X514765Y189764I0J3937D01*
G01X487205Y185827D02*
X510828D01*
G01X483269Y189764D02*
G03X487205Y185828I3937J1D01*
G01X483268Y210237D02*
Y189764D01*
G01Y210237D02*
G03X479331Y214174I-3937J0D01*
G01X475197D02*
G03Y206300I0J-3937D01*
G01Y181890D02*
G03Y174016I0J-3937D01*
G01X475394Y181890D02*
X475197D01*
G01X475394Y206300D02*
Y181890D01*
G01X475197Y206300D02*
X475394D01*
G01X494017Y233859D02*
G03X504017I5000J0D01*
G01D02*
G03X494017I-5000J0D01*
G01X475197Y316536D02*
G03Y308662I0J-3937D01*
G01X493720Y288977D02*
G03X483642I-5039J0D01*
G01D02*
G03X493720I5039J0D01*
G01X518702Y348820D02*
X570079D01*
G01X518702D02*
G03X514765Y344883I0J-3937D01*
G01Y324410D02*
Y344883D01*
G01X510828Y320473D02*
G03X514765Y324410I0J3937D01*
G01X487205Y320473D02*
X510828D01*
G01X483269Y324410D02*
G03X487205Y320474I3937J1D01*
G01X483268Y344883D02*
Y324410D01*
G01Y344883D02*
G03X479331Y348820I-3937J0D01*
G01X475197D02*
G03Y340946I0J-3937D01*
G01X475394Y316536D02*
X475197D01*
G01X475394Y340946D02*
Y316536D01*
G01X475197Y340946D02*
X475394D01*
G01X494017Y368505D02*
G03X504017I5000J0D01*
G01D02*
G03X494017I-5000J0D01*
G01X475197Y451182D02*
G03Y443308I0J-3937D01*
G01X475394Y451182D02*
X475197D01*
G01X475394Y475592D02*
Y451182D01*
G01X493720Y423623D02*
G03X483642I-5039J0D01*
G01D02*
G03X493720I5039J0D01*
G01X494017Y503151D02*
G03X504017I5000J0D01*
G01X518702Y483466D02*
X570079D01*
G01X518702D02*
G03X514765Y479529I0J-3937D01*
G01Y459056D02*
Y479529D01*
G01X510828Y455120D02*
G03X514765Y459057I0J3937D01*
G01X487205Y455119D02*
X510828D01*
G01X483269Y459056D02*
G03X487205Y455120I3937J1D01*
G01X483268Y479529D02*
Y459056D01*
G01Y479529D02*
G03X479331Y483466I-3937J0D01*
G01X475197D02*
G03Y475592I0J-3937D01*
G01D02*
X475394D01*
G01X504017Y503151D02*
G03X494017I-5000J0D01*
G01X514765Y593702D02*
Y614175D01*
G01X510828Y589766D02*
G03X514765Y593703I0J3937D01*
G01X487205Y589765D02*
X510828D01*
G01X483269Y593702D02*
G03X487205Y589766I3937J1D01*
G01X483268Y614175D02*
Y593702D01*
G01X475197Y585828D02*
G03Y577954I0J-3937D01*
G01X475394Y585828D02*
X475197D01*
G01X475394Y610238D02*
Y585828D01*
G01X493720Y558269D02*
G03X483642I-5039J0D01*
G01D02*
G03X493720I5039J0D01*
G01X494017Y637797D02*
G03X504017I5000J0D01*
G01D02*
G03X494017I-5000J0D01*
G01X518702Y618112D02*
X570079D01*
G01X518702D02*
G03X514765Y614175I0J-3937D01*
G01X483268D02*
G03X479331Y618112I-3937J0D01*
G01X475197D02*
G03Y610238I0J-3937D01*
G01D02*
X475394D01*
G01X483642Y692915D02*
G03X493720I5039J0D01*
G01X514765Y728348D02*
Y748821D01*
G01X510828Y724412D02*
G03X514765Y728349I0J3937D01*
G01X487205Y724411D02*
X510828D01*
G01X483269Y728348D02*
G03X487205Y724412I3937J1D01*
G01X483268Y748821D02*
Y728348D01*
G01X475197Y720474D02*
G03Y712600I0J-3937D01*
G01X475394Y720474D02*
X475197D01*
G01X475394Y744884D02*
Y720474D01*
G01X493720Y692915D02*
G03X483642I-5039J0D01*
G01X494017Y772443D02*
G03X504017I5000J0D01*
G01D02*
G03X494017I-5000J0D01*
G01X518702Y752758D02*
X570079D01*
G01X518702D02*
G03X514765Y748821I0J-3937D01*
G01X483268D02*
G03X479331Y752758I-3937J0D01*
G01X475197D02*
G03Y744884I0J-3937D01*
G01D02*
X475394D01*
G01X493720Y827561D02*
G03X483642I-5039J0D01*
G01D02*
G03X493720I5039J0D01*
G01X514765Y862994D02*
Y883467D01*
G01X510828Y859058D02*
G03X514765Y862995I0J3937D01*
G01X487205Y859057D02*
X510828D01*
G01X483269Y862994D02*
G03X487205Y859058I3937J1D01*
G01X483268Y883467D02*
Y862994D01*
G01X475197Y887404D02*
G03Y879530I0J-3937D01*
G01Y855120D02*
G03Y847246I0J-3937D01*
G01X475394Y855120D02*
X475197D01*
G01X475394Y879530D02*
Y855120D01*
G01X475197Y879530D02*
X475394D01*
G01X494017Y907089D02*
G03X504017I5000J0D01*
G01D02*
G03X494017I-5000J0D01*
G01X518702Y887404D02*
X570079D01*
G01X518702D02*
G03X514765Y883467I0J-3937D01*
G01X483268D02*
G03X479331Y887404I-3937J0D01*
G01X530709Y39370D02*
G03X534646Y43307I0J3937D01*
G01Y63780D02*
Y43307D01*
G01X538583Y67717D02*
G03X534646Y63780I0J-3937D01*
G01X562205Y67717D02*
X538583D01*
G01X566142Y63780D02*
G03X562205Y67717I-3937J0D01*
G01X566142Y43307D02*
Y63780D01*
G01Y43307D02*
G03X570079Y39370I3937J0D01*
G01X530709Y174016D02*
G03X534646Y177953I0J3937D01*
G01Y198426D02*
Y177953D01*
G01X538583Y202363D02*
G03X534646Y198426I0J-3937D01*
G01X562205Y202363D02*
X538583D01*
G01X566142Y198426D02*
G03X562205Y202363I-3937J0D01*
G01X566142Y177953D02*
Y198426D01*
G01Y177953D02*
G03X570079Y174016I3937J0D01*
G01X530709Y308662D02*
G03X534646Y312599I0J3937D01*
G01Y333072D02*
Y312599D01*
G01X538583Y337009D02*
G03X534646Y333072I0J-3937D01*
G01X562205Y337009D02*
X538583D01*
G01X566142Y333072D02*
G03X562205Y337009I-3937J0D01*
G01X566142Y312599D02*
Y333072D01*
G01Y312599D02*
G03X570079Y308662I3937J0D01*
G01X530709Y443308D02*
G03X534646Y447245I0J3937D01*
G01Y467718D02*
Y447245D01*
G01X566142D02*
Y467718D01*
G01Y447245D02*
G03X570079Y443308I3937J0D01*
G01X538583Y471655D02*
G03X534646Y467718I0J-3937D01*
G01X562205Y471655D02*
X538583D01*
G01X566142Y467718D02*
G03X562205Y471655I-3937J0D01*
G01X530709Y577954D02*
G03X534646Y581891I0J3937D01*
G01Y602364D02*
Y581891D01*
G01X566142D02*
Y602364D01*
G01Y581891D02*
G03X570079Y577954I3937J0D01*
G01X538583Y606301D02*
G03X534646Y602364I0J-3937D01*
G01X562205Y606301D02*
X538583D01*
G01X566142Y602364D02*
G03X562205Y606301I-3937J0D01*
G01X530709Y712601D02*
G03X534646Y716538I0J3937D01*
G01Y737010D02*
Y716537D01*
G01X538583Y740947D02*
G03X534646Y737010I0J-3937D01*
G01X566142D02*
G03X562205Y740947I-3937J0D01*
G01X566142Y716537D02*
Y737010D01*
G01Y716537D02*
G03X570079Y712600I3937J0D01*
G01X562205Y740947D02*
X538583D01*
G01X530709Y847247D02*
G03X534646Y851184I0J3937D01*
G01Y871656D02*
Y851183D01*
G01X538583Y875593D02*
G03X534646Y871656I0J-3937D01*
G01X562205Y875593D02*
X538583D01*
G01X566142Y871656D02*
G03X562205Y875593I-3937J0D01*
G01X566142Y851183D02*
Y871656D01*
G01Y851183D02*
G03X570079Y847246I3937J0D01*
G01X577954Y47244D02*
X637009D01*
G01X574016Y51181D02*
G03X577954Y47244I3937J0D01*
G01X574016Y75591D02*
Y51181D01*
G01X594883Y39370D02*
G03Y47244I0J3937D01*
G01X654921Y39370D02*
X570079D01*
G01X574016Y75591D02*
G03X570079Y79528I-3937J0D01*
G01X604676Y130709D02*
G03Y122835I0J-3937D01*
G01X579479D02*
G03Y130709I0J3937D01*
G01X577954Y181890D02*
X637009D01*
G01X574016Y185827D02*
G03X577954Y181890I3937J0D01*
G01X574016Y210237D02*
Y185827D01*
G01Y210237D02*
G03X570079Y214174I-3937J0D01*
G01X594883Y174016D02*
G03Y181890I0J3937D01*
G01X654921Y174016D02*
X570079D01*
G01X604676Y265355D02*
G03Y257481I0J-3937D01*
G01X579479D02*
G03Y265355I0J3937D01*
G01X594883Y308662D02*
G03Y316536I0J3937D01*
G01X654921Y308662D02*
X570079D01*
G01X577954Y316536D02*
X637009D01*
G01X574016Y320473D02*
G03X577954Y316536I3937J0D01*
G01X574016Y344883D02*
Y320473D01*
G01Y344883D02*
G03X570079Y348820I-3937J0D01*
G01X604676Y400001D02*
G03Y392127I0J-3937D01*
G01X579479D02*
G03Y400001I0J3937D01*
G01X577954Y451182D02*
X637009D01*
G01X574016Y455120D02*
G03X577954Y451183I3937J0D01*
G01X594883Y443308D02*
G03Y451182I0J3937D01*
G01X654921Y443308D02*
X570079D01*
G01X574016Y479529D02*
Y455119D01*
G01Y479529D02*
G03X570079Y483466I-3937J0D01*
G01X604676Y534647D02*
G03Y526773I0J-3937D01*
G01X579479D02*
G03Y534647I0J3937D01*
G01X577954Y585828D02*
X637009D01*
G01X574016Y589766D02*
G03X577954Y585829I3937J0D01*
G01X574016Y614175D02*
Y589765D01*
G01X594883Y577954D02*
G03Y585828I0J3937D01*
G01X654921Y577954D02*
X570079D01*
G01X574016Y614175D02*
G03X570079Y618112I-3937J0D01*
G01X604676Y669293D02*
G03Y661419I0J-3937D01*
G01X579479D02*
G03Y669293I0J3937D01*
G01X577954Y720474D02*
X637009D01*
G01X574016Y724412D02*
G03X577954Y720475I3937J0D01*
G01X574016Y748821D02*
Y724411D01*
G01X594883Y712600D02*
G03Y720474I0J3937D01*
G01X654921Y712600D02*
X570079D01*
G01X574016Y748821D02*
G03X570079Y752758I-3937J0D01*
G01X604676Y803939D02*
G03Y796065I0J-3937D01*
G01X579479D02*
G03Y803939I0J3937D01*
G01X577954Y855120D02*
X637009D01*
G01X574016Y859058D02*
G03X577954Y855121I3937J0D01*
G01X574016Y883467D02*
Y859057D01*
G01X594883Y847246D02*
G03Y855120I0J3937D01*
G01X654921Y847246D02*
X570079D01*
G01X574016Y883467D02*
G03X570079Y887404I-3937J0D01*
G01X640946Y51181D02*
Y75591D01*
G01X637009Y47244D02*
G03X640946Y51181I0J3937D01*
G01X620080Y47244D02*
G03Y39370I0J-3937D01*
G01X654921D02*
G03X658858Y43307I0J3937D01*
G01Y63780D02*
Y43307D01*
G01X662795Y67717D02*
G03X658858Y63780I0J-3937D01*
G01X644883Y79528D02*
X727757D01*
G01X644883D02*
G03X640946Y75591I0J-3937D01*
G01X644883Y214174D02*
X727757D01*
G01X644883D02*
G03X640946Y210237I0J-3937D01*
G01Y185827D02*
Y210237D01*
G01X637009Y181890D02*
G03X640946Y185827I0J3937D01*
G01X620080Y181890D02*
G03Y174016I0J-3937D01*
G01X654921D02*
G03X658858Y177953I0J3937D01*
G01Y198426D02*
Y177953D01*
G01X662795Y202363D02*
G03X658858Y198426I0J-3937D01*
G01X620080Y316536D02*
G03Y308662I0J-3937D01*
G01X654921D02*
G03X658858Y312599I0J3937D01*
G01X644883Y348820D02*
X727757D01*
G01X644883D02*
G03X640946Y344883I0J-3937D01*
G01Y320473D02*
Y344883D01*
G01X637009Y316536D02*
G03X640946Y320473I0J3937D01*
G01X658858Y333072D02*
Y312599D01*
G01X662795Y337009D02*
G03X658858Y333072I0J-3937D01*
G01X637009Y451183D02*
G03X640946Y455120I0J3937D01*
G01X620080Y451182D02*
G03Y443308I0J-3937D01*
G01X654921D02*
G03X658858Y447245I0J3937D01*
G01Y467718D02*
Y447245D01*
G01X644883Y483466D02*
X727757D01*
G01X644883D02*
G03X640946Y479529I0J-3937D01*
G01Y455119D02*
Y479529D01*
G01X662795Y471655D02*
G03X658858Y467718I0J-3937D01*
G01X640946Y589765D02*
Y614175D01*
G01X637009Y585829D02*
G03X640946Y589766I0J3937D01*
G01X620080Y585828D02*
G03Y577954I0J-3937D01*
G01X654921D02*
G03X658858Y581891I0J3937D01*
G01Y602364D02*
Y581891D01*
G01X644883Y618112D02*
X727757D01*
G01X644883D02*
G03X640946Y614175I0J-3937D01*
G01X662795Y606301D02*
G03X658858Y602364I0J-3937D01*
G01X640946Y724411D02*
Y748821D01*
G01X637009Y720475D02*
G03X640946Y724412I0J3937D01*
G01X620080Y720474D02*
G03Y712600I0J-3937D01*
G01X654921D02*
G03X658858Y716537I0J3937D01*
G01Y737010D02*
Y716537D01*
G01X662795Y740947D02*
G03X658858Y737010I0J-3937D01*
G01X644883Y752758D02*
X727757D01*
G01X644883D02*
G03X640946Y748821I0J-3937D01*
G01Y859057D02*
Y883467D01*
G01X637009Y855121D02*
G03X640946Y859058I0J3937D01*
G01X620080Y855120D02*
G03Y847246I0J-3937D01*
G01X654921D02*
G03X658858Y851183I0J3937D01*
G01Y871656D02*
Y851183D01*
G01X662795Y875593D02*
G03X658858Y871656I0J-3937D01*
G01X644883Y887404D02*
X727757D01*
G01X644883D02*
G03X640946Y883467I0J-3937D01*
G01X686319Y19685D02*
G03X674902I-5708J0D01*
G01D02*
G03X686319I5708J0D01*
G01X717106D02*
G03X707106I-5000J0D01*
G01D02*
G03X717106I5000J0D01*
G01X701969Y39370D02*
G03Y47244I0J3937D01*
G01Y71654D02*
G03Y79528I0J3937D01*
G01X698228Y71654D02*
X701969D01*
G01X698228Y47244D02*
Y71654D01*
G01X701969Y47244D02*
X698228D01*
G01X686417Y67717D02*
X662795D01*
G01X690354Y63780D02*
G03X686417Y67717I-3937J0D01*
G01X690354Y43307D02*
Y63780D01*
G01Y43307D02*
G03X694291Y39370I3937J0D01*
G01X724409D02*
X694291D01*
G01X686319Y154331D02*
G03X674902I-5708J0D01*
G01D02*
G03X686319I5708J0D01*
G01X717106D02*
G03X707106I-5000J0D01*
G01D02*
G03X717106I5000J0D01*
G01X701969Y174016D02*
G03Y181890I0J3937D01*
G01Y206300D02*
G03Y214174I0J3937D01*
G01X698228Y206300D02*
X701969D01*
G01X698228Y181890D02*
Y206300D01*
G01X701969Y181890D02*
X698228D01*
G01X686417Y202363D02*
X662795D01*
G01X690354Y198426D02*
G03X686417Y202363I-3937J0D01*
G01X690354Y177953D02*
Y198426D01*
G01Y177953D02*
G03X694291Y174016I3937J0D01*
G01X724409D02*
X694291D01*
G01X701969Y308662D02*
G03Y316536I0J3937D01*
G01X686319Y288977D02*
G03X674902I-5708J0D01*
G01D02*
G03X686319I5708J0D01*
G01X717106D02*
G03X707106I-5000J0D01*
G01D02*
G03X717106I5000J0D01*
G01X690354Y312599D02*
G03X694291Y308662I3937J0D01*
G01X724409D02*
X694291D01*
G01X701969Y340946D02*
G03Y348820I0J3937D01*
G01X698228Y340946D02*
X701969D01*
G01X698228Y316536D02*
Y340946D01*
G01X701969Y316536D02*
X698228D01*
G01X686417Y337009D02*
X662795D01*
G01X690354Y333072D02*
G03X686417Y337009I-3937J0D01*
G01X690354Y312599D02*
Y333072D01*
G01X701969Y443308D02*
G03Y451182I0J3937D01*
G01X698228D02*
Y475592D01*
G01X701969Y451182D02*
X698228D01*
G01X686319Y423623D02*
G03X674902I-5708J0D01*
G01D02*
G03X686319I5708J0D01*
G01X717106D02*
G03X707106I-5000J0D01*
G01D02*
G03X717106I5000J0D01*
G01X690354Y447245D02*
Y467718D01*
G01Y447245D02*
G03X694291Y443308I3937J0D01*
G01X724409D02*
X694291D01*
G01X701969Y475592D02*
G03Y483466I0J3937D01*
G01X698228Y475592D02*
X701969D01*
G01X686417Y471655D02*
X662795D01*
G01X690354Y467718D02*
G03X686417Y471655I-3937J0D01*
G01X701969Y577954D02*
G03Y585828I0J3937D01*
G01X698228D02*
Y610238D01*
G01X701969Y585828D02*
X698228D01*
G01X686319Y558269D02*
G03X674902I-5708J0D01*
G01D02*
G03X686319I5708J0D01*
G01X717106D02*
G03X707106I-5000J0D01*
G01D02*
G03X717106I5000J0D01*
G01X690354Y581891D02*
Y602364D01*
G01Y581891D02*
G03X694291Y577954I3937J0D01*
G01X724409D02*
X694291D01*
G01X701969Y610238D02*
G03Y618112I0J3937D01*
G01X698228Y610238D02*
X701969D01*
G01X686417Y606301D02*
X662795D01*
G01X690354Y602364D02*
G03X686417Y606301I-3937J0D01*
G01X674902Y692915D02*
G03X686319I5708J0D01*
G01X707106D02*
G03X717106I5000J0D01*
G01X701969Y712600D02*
G03Y720474I0J3937D01*
G01X698228D02*
Y744884D01*
G01X701969Y720474D02*
X698228D01*
G01X686319Y692915D02*
G03X674902I-5708J0D01*
G01X717106D02*
G03X707106I-5000J0D01*
G01X690354Y737010D02*
G03X686417Y740947I-3937J0D01*
G01X690354Y716537D02*
Y737010D01*
G01Y716538D02*
G03X694291Y712601I3937J0D01*
G01X724409Y712600D02*
X694291D01*
G01X701969Y744884D02*
G03Y752758I0J3937D01*
G01X698228Y744884D02*
X701969D01*
G01X686417Y740947D02*
X662795D01*
G01X686319Y827561D02*
G03X674902I-5708J0D01*
G01D02*
G03X686319I5708J0D01*
G01X717106D02*
G03X707106I-5000J0D01*
G01D02*
G03X717106I5000J0D01*
G01X701969Y847246D02*
G03Y855120I0J3937D01*
G01Y879530D02*
G03Y887404I0J3937D01*
G01X698228Y879530D02*
X701969D01*
G01X698228Y855120D02*
Y879530D01*
G01X701969Y855120D02*
X698228D01*
G01X686417Y875593D02*
X662795D01*
G01X690354Y871656D02*
G03X686417Y875593I-3937J0D01*
G01X690354Y851183D02*
Y871656D01*
G01Y851184D02*
G03X694291Y847247I3937J0D01*
G01X724409Y847246D02*
X694291D01*
G01X736220Y0D02*
G03X740157Y-3937I3937J0D01*
G01X736220Y5118D02*
Y0D01*
G01X740157Y-3937D02*
X793111D01*
G01X736220Y5118D02*
G03X728346I-3937J0D01*
G01X724409Y-3937D02*
G03X728346Y0I0J3937D01*
G01D02*
Y35433D01*
G01X720079Y47244D02*
G03Y39370I0J-3937D01*
G01Y79528D02*
G03Y71654I0J-3937D01*
G01X723820D02*
Y47244D01*
G01X720079Y71654D02*
X723820D01*
G01Y47244D02*
X720079D01*
G01X740157Y43307D02*
G03X736220Y39370I0J-3937D01*
G01X740157Y43307D02*
X759253D01*
G01X736220Y30315D02*
Y39370D01*
G01X735631Y51181D02*
X759253D01*
G01X731694Y55118D02*
G03X735631Y51181I3937J0D01*
G01X731694Y75591D02*
Y55118D01*
G01X728346Y30315D02*
G03X736220I3937J0D01*
G01X728346Y35433D02*
G03X724409Y39370I-3937J0D01*
G01X747540Y99213D02*
G03X758957I5708J0D01*
G01D02*
G03X747540I-5709J0D01*
G01X731694Y75591D02*
G03X727757Y79528I-3937J0D01*
G01X736220Y134646D02*
G03X740157Y130709I3937J0D01*
G01X771064D02*
X740157D01*
G01X736220Y139764D02*
Y134646D01*
G01X728346Y164961D02*
G03X736220I3937J0D01*
G01Y139764D02*
G03X728346I-3937J0D01*
G01X724409Y130709D02*
G03X728346Y134646I0J3937D01*
G01X736220Y164961D02*
Y174016D01*
G01X728346Y134646D02*
Y170079D01*
G01X720079Y181890D02*
G03Y174016I0J-3937D01*
G01Y214174D02*
G03Y206300I0J-3937D01*
G01X723820D02*
Y181890D01*
G01X720079Y206300D02*
X723820D01*
G01Y181890D02*
X720079D01*
G01X740157Y177953D02*
G03X736220Y174016I0J-3937D01*
G01X740157Y177953D02*
X759253D01*
G01X735631Y185827D02*
X759253D01*
G01X731694Y189764D02*
G03X735631Y185827I3937J0D01*
G01X731694Y210237D02*
Y189764D01*
G01Y210237D02*
G03X727757Y214174I-3937J0D01*
G01X728346Y170079D02*
G03X724409Y174016I-3937J0D01*
G01X747540Y233859D02*
G03X758957I5708J0D01*
G01D02*
G03X747540I-5709J0D01*
G01X720079Y316536D02*
G03Y308662I0J-3937D01*
G01X736220Y269292D02*
G03X740157Y265355I3937J0D01*
G01Y312599D02*
G03X736220Y308662I0J-3937D01*
G01X771064Y265355D02*
X740157D01*
G01X736220Y274410D02*
Y269292D01*
G01X728346Y299607D02*
G03X736220I3937J0D01*
G01Y274410D02*
G03X728346I-3937J0D01*
G01X736220Y299607D02*
Y308662D01*
G01X724409Y265355D02*
G03X728346Y269292I0J3937D01*
G01Y304725D02*
G03X724409Y308662I-3937J0D01*
G01X728346Y269292D02*
Y304725D01*
G01X720079Y348820D02*
G03Y340946I0J-3937D01*
G01X723820D02*
Y316536D01*
G01X720079Y340946D02*
X723820D01*
G01Y316536D02*
X720079D01*
G01X740157Y312599D02*
X759253D01*
G01X735631Y320473D02*
X759253D01*
G01X731694Y324410D02*
G03X735631Y320473I3937J0D01*
G01X731694Y344883D02*
Y324410D01*
G01Y344883D02*
G03X727757Y348820I-3937J0D01*
G01X736220Y403938D02*
G03X740157Y400001I3937J0D01*
G01X771064D02*
X740157D01*
G01X736220Y409056D02*
Y403938D01*
G01X724409Y400001D02*
G03X728346Y403938I0J3937D01*
G01D02*
Y439371D01*
G01X747540Y368505D02*
G03X758957I5708J0D01*
G01D02*
G03X747540I-5709J0D01*
G01X720079Y451182D02*
G03Y443308I0J-3937D01*
G01X723820Y475592D02*
Y451182D01*
G01D02*
X720079D01*
G01X740157Y447245D02*
G03X736220Y443308I0J-3937D01*
G01X740157Y447245D02*
X759253D01*
G01X728346Y434253D02*
G03X736220I3937J0D01*
G01Y409056D02*
G03X728346I-3937J0D01*
G01X736220Y434253D02*
Y443308D01*
G01X728346Y439371D02*
G03X724409Y443308I-3937J0D01*
G01X720079Y483466D02*
G03Y475592I0J-3937D01*
G01D02*
X723820D01*
G01X747540Y503151D02*
G03X758957I5708J0D01*
G01X735631Y455119D02*
X759253D01*
G01X731694Y459056D02*
G03X735631Y455119I3937J0D01*
G01X731694Y479529D02*
Y459056D01*
G01Y479529D02*
G03X727757Y483466I-3937J0D01*
G01X736220Y538584D02*
G03X740157Y534647I3937J0D01*
G01X771064D02*
X740157D01*
G01X736220Y543702D02*
Y538584D01*
G01Y543702D02*
G03X728346I-3937J0D01*
G01X724409Y534647D02*
G03X728346Y538584I0J3937D01*
G01D02*
Y574017D01*
G01X758957Y503151D02*
G03X747540I-5709J0D01*
G01X720079Y585828D02*
G03Y577954I0J-3937D01*
G01X723820Y610238D02*
Y585828D01*
G01D02*
X720079D01*
G01X740157Y581891D02*
G03X736220Y577954I0J-3937D01*
G01X740157Y581891D02*
X759253D01*
G01X728346Y568899D02*
G03X736220I3937J0D01*
G01D02*
Y577954D01*
G01X735631Y589765D02*
X759253D01*
G01X731694Y593702D02*
G03X735631Y589765I3937J0D01*
G01X731694Y614175D02*
Y593702D01*
G01X728346Y574017D02*
G03X724409Y577954I-3937J0D01*
G01X720079Y618112D02*
G03Y610238I0J-3937D01*
G01D02*
X723820D01*
G01X747540Y637797D02*
G03X758957I5708J0D01*
G01D02*
G03X747540I-5709J0D01*
G01X731694Y614175D02*
G03X727757Y618112I-3937J0D01*
G01X736220Y673230D02*
G03X740157Y669293I3937J0D01*
G01X771064D02*
X740157D01*
G01X736220Y678348D02*
Y673230D01*
G01Y678348D02*
G03X728346I-3937J0D01*
G01X724409Y669293D02*
G03X728346Y673230I0J3937D01*
G01D02*
Y708663D01*
G01X720079Y720474D02*
G03Y712600I0J-3937D01*
G01X723820Y744884D02*
Y720474D01*
G01D02*
X720079D01*
G01X740157Y716537D02*
G03X736220Y712600I0J-3937D01*
G01X740157Y716537D02*
X759253D01*
G01X728346Y703545D02*
G03X736220I3937J0D01*
G01D02*
Y712600D01*
G01X735631Y724411D02*
X759253D01*
G01X731694Y728348D02*
G03X735631Y724411I3937J0D01*
G01X731694Y748821D02*
Y728348D01*
G01X728346Y708664D02*
G03X724409Y712601I-3937J0D01*
G01X720079Y752758D02*
G03Y744884I0J-3937D01*
G01D02*
X723820D01*
G01X747540Y772443D02*
G03X758957I5708J0D01*
G01D02*
G03X747540I-5709J0D01*
G01X731694Y748821D02*
G03X727757Y752758I-3937J0D01*
G01X736220Y807876D02*
G03X740157Y803939I3937J0D01*
G01X771064D02*
X740157D01*
G01X736220Y812995D02*
Y807876D01*
G01X728346Y838191D02*
G03X736220I3937J0D01*
G01Y812995D02*
G03X728346I-3937J0D01*
G01X724409Y803939D02*
G03X728346Y807876I0J3937D01*
G01D02*
Y843309D01*
G01X720079Y855120D02*
G03Y847246I0J-3937D01*
G01Y887404D02*
G03Y879530I0J-3937D01*
G01X723820D02*
Y855120D01*
G01X720079Y879530D02*
X723820D01*
G01Y855120D02*
X720079D01*
G01X740157Y851183D02*
G03X736220Y847246I0J-3937D01*
G01X740157Y851183D02*
X759253D01*
G01X736220Y838191D02*
Y847246D01*
G01X735631Y859057D02*
X759253D01*
G01X731694Y862994D02*
G03X735631Y859057I3937J0D01*
G01X731694Y883467D02*
Y862994D01*
G01X728346Y843310D02*
G03X724409Y847247I-3937J0D01*
G01X747540Y907089D02*
G03X758957I5708J0D01*
G01D02*
G03X747540I-5709J0D01*
G01X731694Y883467D02*
G03X727757Y887404I-3937J0D01*
G01X793111Y-3937D02*
G03X800985Y3937I0J7874D01*
G01Y67717D02*
Y3937D01*
G01X789036Y19685D02*
G03I-4291J0D01*
G01X800985Y67717D02*
G03X797048Y71654I-3937J0D01*
G01X771064Y55118D02*
Y71654D01*
G01X796261D02*
X797048D01*
G01X759253Y43307D02*
G03X771064Y55118I0J11811D01*
G01X763190D02*
Y75591D01*
G01X759253Y51181D02*
G03X763190Y55118I0J3937D01*
G01X796261Y79528D02*
G03Y71654I0J-3937D01*
G01X771064D02*
G03Y79528I0J3937D01*
G01X779706Y99213D02*
G03X789784I5039J0D01*
G01D02*
G03X779706I-5039J0D01*
G01X800985Y118898D02*
G03X797048Y122835I-3937J0D01*
G01X800985Y83465D02*
Y118898D01*
G01X797048Y79528D02*
G03X800985Y83465I0J3937D01*
G01X767127Y79528D02*
X797048D01*
G01X767127D02*
G03X763190Y75591I0J-3937D01*
G01X797048Y130709D02*
G03X800985Y134646I0J3937D01*
G01X796261Y130709D02*
X797048D01*
G01X800985Y202363D02*
Y134646D01*
G01X789036Y154331D02*
G03I-4291J0D01*
G01X771064Y122835D02*
G03Y130709I0J3937D01*
G01X796261D02*
G03Y122835I0J-3937D01*
G01X800985Y202363D02*
G03X797048Y206300I-3937J0D01*
G01Y214174D02*
G03X800985Y218111I0J3937D01*
G01X796261Y206300D02*
X797048D01*
G01X767127Y214174D02*
X797048D01*
G01X767127D02*
G03X763190Y210237I0J-3937D01*
G01X771064Y189764D02*
Y206300D01*
G01X763190Y189764D02*
Y210237D01*
G01X759253Y177953D02*
G03X771064Y189764I0J11811D01*
G01X759253Y185827D02*
G03X763190Y189764I0J3937D01*
G01X796261Y214174D02*
G03Y206300I0J-3937D01*
G01X771064D02*
G03Y214174I0J3937D01*
G01Y257481D02*
G03Y265355I0J3937D01*
G01X796261D02*
G03Y257481I0J-3937D01*
G01X779706Y233859D02*
G03X789784I5039J0D01*
G01D02*
G03X779706I-5039J0D01*
G01X800985Y253544D02*
G03X797048Y257481I-3937J0D01*
G01X800985Y218111D02*
Y253544D01*
G01X797048Y265355D02*
G03X800985Y269292I0J3937D01*
G01X796261Y265355D02*
X797048D01*
G01X800985Y337009D02*
Y269292D01*
G01X789036Y288977D02*
G03I-4291J0D01*
G01X800985Y337009D02*
G03X797048Y340946I-3937J0D01*
G01X796261D02*
X797048D01*
G01X771064Y324410D02*
Y340946D01*
G01X759253Y312599D02*
G03X771064Y324410I0J11811D01*
G01X796261Y348820D02*
G03Y340946I0J-3937D01*
G01X771064D02*
G03Y348820I0J3937D01*
G01X800985Y352757D02*
Y388190D01*
G01X797048Y348820D02*
G03X800985Y352757I0J3937D01*
G01X767127Y348820D02*
X797048D01*
G01X767127D02*
G03X763190Y344883I0J-3937D01*
G01Y324410D02*
Y344883D01*
G01X759253Y320473D02*
G03X763190Y324410I0J3937D01*
G01X797048Y400001D02*
G03X800985Y403938I0J3937D01*
G01X796261Y400001D02*
X797048D01*
G01X800985Y471655D02*
Y403938D01*
G01X771064Y392127D02*
G03Y400001I0J3937D01*
G01X796261D02*
G03Y392127I0J-3937D01*
G01X779706Y368505D02*
G03X789784I5039J0D01*
G01D02*
G03X779706I-5039J0D01*
G01X800985Y388190D02*
G03X797048Y392127I-3937J0D01*
G01X759253Y447246D02*
G03X771064Y459057I0J11811D01*
G01X789036Y423623D02*
G03I-4291J0D01*
G01X800985Y471655D02*
G03X797048Y475592I-3937J0D01*
G01X796261D02*
X797048D01*
G01X771064Y459056D02*
Y475592D01*
G01X796261Y483466D02*
G03Y475592I0J-3937D01*
G01X771064D02*
G03Y483466I0J3937D01*
G01X779706Y503151D02*
G03X789784I5039J0D01*
G01X800985Y487403D02*
Y522836D01*
G01X797048Y483466D02*
G03X800985Y487403I0J3937D01*
G01X767127Y483466D02*
X797048D01*
G01X767127D02*
G03X763190Y479529I0J-3937D01*
G01Y459056D02*
Y479529D01*
G01X759253Y455120D02*
G03X763190Y459057I0J3937D01*
G01X797048Y534647D02*
G03X800985Y538584I0J3937D01*
G01X796261Y534647D02*
X797048D01*
G01X800985Y606301D02*
Y538584D01*
G01X771064Y526773D02*
G03Y534647I0J3937D01*
G01X796261D02*
G03Y526773I0J-3937D01*
G01X789784Y503151D02*
G03X779706I-5039J0D01*
G01X800985Y522836D02*
G03X797048Y526773I-3937J0D01*
G01X771064Y593702D02*
Y610238D01*
G01X759253Y581892D02*
G03X771064Y593703I0J11811D01*
G01X789036Y558269D02*
G03I-4291J0D01*
G01X763190Y593702D02*
Y614175D01*
G01X759253Y589766D02*
G03X763190Y593703I0J3937D01*
G01X800985Y606301D02*
G03X797048Y610238I-3937J0D01*
G01X796261D02*
X797048D01*
G01X796261Y618112D02*
G03Y610238I0J-3937D01*
G01X771064D02*
G03Y618112I0J3937D01*
G01X779706Y637797D02*
G03X789784I5039J0D01*
G01D02*
G03X779706I-5039J0D01*
G01X800985Y622049D02*
Y657482D01*
G01X797048Y618112D02*
G03X800985Y622049I0J3937D01*
G01X767127Y618112D02*
X797048D01*
G01X767127D02*
G03X763190Y614175I0J-3937D01*
G01X797048Y669293D02*
G03X800985Y673230I0J3937D01*
G01X796261Y669293D02*
X797048D01*
G01X800985Y740947D02*
Y673230D01*
G01X789036Y692915D02*
G03I-4291J0D01*
G01X771064Y661419D02*
G03Y669293I0J3937D01*
G01X796261D02*
G03Y661419I0J-3937D01*
G01X800985Y657482D02*
G03X797048Y661419I-3937J0D01*
G01X771064Y728348D02*
Y744884D01*
G01X759253Y716538D02*
G03X771064Y728349I0J11811D01*
G01X763190Y728348D02*
Y748821D01*
G01X759253Y724412D02*
G03X763190Y728349I0J3937D01*
G01X800985Y740947D02*
G03X797048Y744884I-3937J0D01*
G01X796261D02*
X797048D01*
G01X796261Y752758D02*
G03Y744884I0J-3937D01*
G01X771064D02*
G03Y752758I0J3937D01*
G01X779706Y772443D02*
G03X789784I5039J0D01*
G01D02*
G03X779706I-5039J0D01*
G01X800985Y756695D02*
Y792128D01*
G01X797048Y752758D02*
G03X800985Y756695I0J3937D01*
G01X767127Y752758D02*
X797048D01*
G01X767127D02*
G03X763190Y748821I0J-3937D01*
G01X800985Y855100D02*
Y807876D01*
G01X797048Y803939D02*
G03X800985Y807876I0J3937D01*
G01X796261Y803939D02*
X797048D01*
G01X789036Y827561D02*
G03I-4291J0D01*
G01X771064Y796065D02*
G03Y803939I0J3937D01*
G01X796261D02*
G03Y796065I0J-3937D01*
G01X800985Y792128D02*
G03X797048Y796065I-3937J0D01*
G01X800985Y862974D02*
G03Y855100I0J-3937D01*
G01Y875593D02*
G03X797048Y879530I-3937J0D01*
G01X800985Y875593D02*
Y862974D01*
G01X796261Y879530D02*
X797048D01*
G01X771064Y862994D02*
Y879530D01*
G01X759253Y851184D02*
G03X771064Y862995I0J11811D01*
G01X796261Y887404D02*
G03Y879530I0J-3937D01*
G01X771064D02*
G03Y887404I0J3937D01*
G01X763190Y862994D02*
Y883467D01*
G01X759253Y859058D02*
G03X763190Y862995I0J3937D01*
G01X779706Y907089D02*
G03X789784I5039J0D01*
G01D02*
G03X779706I-5039J0D01*
G01X800985Y926774D02*
G03X797048Y930711I-3937J0D01*
G01X800985Y891341D02*
Y926774D01*
G01X797048Y887404D02*
G03X800985Y891341I0J3937D01*
G01X767127Y887404D02*
X797048D01*
G01X767127D02*
G03X763190Y883467I0J-3937D01*
M02*
